G04 ================== begin FILE IDENTIFICATION RECORD ==================*
G04 Layout Name:  D:/<user>/Wistron_project/16316-1/gbr-0621/16316-1.brd*
G04 Film Name:    L1*
G04 File Format:  Gerber RS274X*
G04 File Origin:  Cadence Allegro 16.5-S056*
G04 Origin Date:  Wed Jun 21 09:31:59 2017*
G04 *
G04 Layer:  VIA CLASS/TOP*
G04 Layer:  PIN/TOP*
G04 Layer:  ETCH/TOP*
G04 Layer:  DRAWING FORMAT/LAYER_PCB_STORY*
G04 Layer:  DRAWING FORMAT/LAYER_L1*
G04 *
G04 Offset:    (0.00 0.00)*
G04 Mirror:    No*
G04 Mode:      Positive*
G04 Rotation:  0*
G04 FullContactRelief:  No*
G04 UndefLineWidth:     6.00*
G04 ================== end FILE IDENTIFICATION RECORD ====================*
%FSLAX35Y35*MOIN*%
%IR0*IPPOS*OFA0.00000B0.00000*MIA0B0*SFA1.00000B1.00000*%
%AMMACRO78*
4,1,40,.013,.017,
-.013,.017,
-.013695,.016939,
-.014368,.016759,
-.015,.016464,
-.015571,.016064,
-.016064,.015571,
-.016464,.015,
-.016759,.014368,
-.016939,.013695,
-.017,.013,
-.017,-.013,
-.016939,-.013695,
-.016759,-.014368,
-.016464,-.015,
-.016064,-.015571,
-.015571,-.016064,
-.015,-.016464,
-.014368,-.016759,
-.013695,-.016939,
-.013,-.017,
.013,-.017,
.013695,-.016939,
.014368,-.016759,
.015,-.016464,
.015571,-.016064,
.016064,-.015571,
.016464,-.015,
.016759,-.014368,
.016939,-.013695,
.017,-.013,
.017,.013,
.016939,.013695,
.016759,.014368,
.016464,.015,
.016064,.015571,
.015571,.016064,
.015,.016464,
.014368,.016759,
.013695,.016939,
.013,.017,
0.0*
%
%ADD78MACRO78*%
%AMMACRO39*
4,1,40,.017,-.013,
.017,.013,
.016939,.013695,
.016759,.014368,
.016464,.015,
.016064,.015571,
.015571,.016064,
.015,.016464,
.014368,.016759,
.013695,.016939,
.013,.017,
-.013,.017,
-.013695,.016939,
-.014368,.016759,
-.015,.016464,
-.015571,.016064,
-.016064,.015571,
-.016464,.015,
-.016759,.014368,
-.016939,.013695,
-.017,.013,
-.017,-.013,
-.016939,-.013695,
-.016759,-.014368,
-.016464,-.015,
-.016064,-.015571,
-.015571,-.016064,
-.015,-.016464,
-.014368,-.016759,
-.013695,-.016939,
-.013,-.017,
.013,-.017,
.013695,-.016939,
.014368,-.016759,
.015,-.016464,
.015571,-.016064,
.016064,-.015571,
.016464,-.015,
.016759,-.014368,
.016939,-.013695,
.017,-.013,
0.0*
%
%ADD39MACRO39*%
%ADD10C,.01*%
%ADD31C,.02*%
%ADD110R,.147X.014*%
%ADD86C,.03*%
%ADD76R,.122X.093*%
%ADD45C,.022*%
%ADD12C,.04*%
%ADD104C,.014*%
%AMMACRO94*
4,1,40,-.007,.004,
-.007,-.004,
-.00697,-.004347,
-.006879,-.004684,
-.006732,-.005,
-.006532,-.005286,
-.006286,-.005532,
-.006,-.005732,
-.005684,-.005879,
-.005347,-.00597,
-.005,-.006,
.005,-.006,
.005347,-.00597,
.005684,-.005879,
.006,-.005732,
.006286,-.005532,
.006532,-.005286,
.006732,-.005,
.006879,-.004684,
.00697,-.004347,
.007,-.004,
.007,.004,
.00697,.004347,
.006879,.004684,
.006732,.005,
.006532,.005286,
.006286,.005532,
.006,.005732,
.005684,.005879,
.005347,.00597,
.005,.006,
-.005,.006,
-.005347,.00597,
-.005684,.005879,
-.006,.005732,
-.006286,.005532,
-.006532,.005286,
-.006732,.005,
-.006879,.004684,
-.00697,.004347,
-.007,.004,
0.0*
%
%ADD94MACRO94*%
%ADD74R,.06X.008*%
%ADD97R,.008X.06*%
%ADD105C,.016*%
%ADD33C,.034*%
%ADD60R,.039X.108*%
%ADD32C,.026*%
%ADD101R,.039X.118*%
%ADD89C,.018*%
%ADD61O,.048X.166*%
%ADD11C,.028*%
%ADD90C,.029*%
%ADD62C,.048*%
%ADD70R,.07X.07*%
%AMMACRO100*
4,1,40,.008,-.014,
-.008,-.014,
-.008695,-.013939,
-.009368,-.013759,
-.01,-.013464,
-.010571,-.013064,
-.011064,-.012571,
-.011464,-.012,
-.011759,-.011368,
-.011939,-.010695,
-.012,-.01,
-.012,.01,
-.011939,.010695,
-.011759,.011368,
-.011464,.012,
-.011064,.012571,
-.010571,.013064,
-.01,.013464,
-.009368,.013759,
-.008695,.013939,
-.008,.014,
.008,.014,
.008695,.013939,
.009368,.013759,
.01,.013464,
.010571,.013064,
.011064,.012571,
.011464,.012,
.011759,.011368,
.011939,.010695,
.012,.01,
.012,-.01,
.011939,-.010695,
.011759,-.011368,
.011464,-.012,
.011064,-.012571,
.010571,-.013064,
.01,-.013464,
.009368,-.013759,
.008695,-.013939,
.008,-.014,
0.0*
%
%ADD100MACRO100*%
%ADD55C,.078*%
%AMMACRO47*
4,1,40,.0225,-.007,
.022378,-.008389,
.022018,-.009736,
.021428,-.011,
.020628,-.012142,
.019642,-.013128,
.0185,-.013928,
.017236,-.014518,
.015889,-.014878,
.0145,-.015,
-.0145,-.015,
-.015889,-.014878,
-.017236,-.014518,
-.0185,-.013928,
-.019642,-.013128,
-.020628,-.012142,
-.021428,-.011,
-.022018,-.009736,
-.022378,-.008389,
-.0225,-.007,
-.0225,.007,
-.022378,.008389,
-.022018,.009736,
-.021428,.011,
-.020628,.012142,
-.019642,.013128,
-.0185,.013928,
-.017236,.014518,
-.015889,.014878,
-.0145,.015,
.0145,.015,
.015889,.014878,
.017236,.014518,
.0185,.013928,
.019642,.013128,
.020628,.012142,
.021428,.011,
.022018,.009736,
.022378,.008389,
.0225,.007,
.0225,-.007,
0.0*
%
%ADD47MACRO47*%
%AMMACRO108*
4,1,40,-.007,-.0225,
-.008389,-.022378,
-.009736,-.022018,
-.011,-.021428,
-.012142,-.020628,
-.013128,-.019642,
-.013928,-.0185,
-.014518,-.017236,
-.014878,-.015889,
-.015,-.0145,
-.015,.0145,
-.014878,.015889,
-.014518,.017236,
-.013928,.0185,
-.013128,.019642,
-.012142,.020628,
-.011,.021428,
-.009736,.022018,
-.008389,.022378,
-.007,.0225,
.007,.0225,
.008389,.022378,
.009736,.022018,
.011,.021428,
.012142,.020628,
.013128,.019642,
.013928,.0185,
.014518,.017236,
.014878,.015889,
.015,.0145,
.015,-.0145,
.014878,-.015889,
.014518,-.017236,
.013928,-.0185,
.013128,-.019642,
.012142,-.020628,
.011,-.021428,
.009736,-.022018,
.008389,-.022378,
.007,-.0225,
-.007,-.0225,
0.0*
%
%ADD108MACRO108*%
%ADD56C,.099*%
%AMMACRO21*
4,1,40,.011,-.007,
.011,.007,
.010939,.007695,
.010759,.008368,
.010464,.009,
.010064,.009571,
.009571,.010064,
.009,.010464,
.008368,.010759,
.007695,.010939,
.007,.011,
-.007,.011,
-.007695,.010939,
-.008368,.010759,
-.009,.010464,
-.009571,.010064,
-.010064,.009571,
-.010464,.009,
-.010759,.008368,
-.010939,.007695,
-.011,.007,
-.011,-.007,
-.010939,-.007695,
-.010759,-.008368,
-.010464,-.009,
-.010064,-.009571,
-.009571,-.010064,
-.009,-.010464,
-.008368,-.010759,
-.007695,-.010939,
-.007,-.011,
.007,-.011,
.007695,-.010939,
.008368,-.010759,
.009,-.010464,
.009571,-.010064,
.010064,-.009571,
.010464,-.009,
.010759,-.008368,
.010939,-.007695,
.011,-.007,
0.0*
%
%ADD21MACRO21*%
%AMMACRO13*
4,1,40,.007,.011,
-.007,.011,
-.007695,.010939,
-.008368,.010759,
-.009,.010464,
-.009571,.010064,
-.010064,.009571,
-.010464,.009,
-.010759,.008368,
-.010939,.007695,
-.011,.007,
-.011,-.007,
-.010939,-.007695,
-.010759,-.008368,
-.010464,-.009,
-.010064,-.009571,
-.009571,-.010064,
-.009,-.010464,
-.008368,-.010759,
-.007695,-.010939,
-.007,-.011,
.007,-.011,
.007695,-.010939,
.008368,-.010759,
.009,-.010464,
.009571,-.010064,
.010064,-.009571,
.010464,-.009,
.010759,-.008368,
.010939,-.007695,
.011,-.007,
.011,.007,
.010939,.007695,
.010759,.008368,
.010464,.009,
.010064,.009571,
.009571,.010064,
.009,.010464,
.008368,.010759,
.007695,.010939,
.007,.011,
0.0*
%
%ADD13MACRO13*%
%AMMACRO49*
4,1,40,-.012,.008,
-.012,-.008,
-.011939,-.008695,
-.011759,-.009368,
-.011464,-.01,
-.011064,-.010571,
-.010571,-.011064,
-.01,-.011464,
-.009368,-.011759,
-.008695,-.011939,
-.008,-.012,
.008,-.012,
.008695,-.011939,
.009368,-.011759,
.01,-.011464,
.010571,-.011064,
.011064,-.010571,
.011464,-.01,
.011759,-.009368,
.011939,-.008695,
.012,-.008,
.012,.008,
.011939,.008695,
.011759,.009368,
.011464,.01,
.011064,.010571,
.010571,.011064,
.01,.011464,
.009368,.011759,
.008695,.011939,
.008,.012,
-.008,.012,
-.008695,.011939,
-.009368,.011759,
-.01,.011464,
-.010571,.011064,
-.011064,.010571,
-.011464,.01,
-.011759,.009368,
-.011939,.008695,
-.012,.008,
0.0*
%
%ADD49MACRO49*%
%AMMACRO20*
4,1,40,.008,.012,
-.008,.012,
-.008695,.011939,
-.009368,.011759,
-.01,.011464,
-.010571,.011064,
-.011064,.010571,
-.011464,.01,
-.011759,.009368,
-.011939,.008695,
-.012,.008,
-.012,-.008,
-.011939,-.008695,
-.011759,-.009368,
-.011464,-.01,
-.011064,-.010571,
-.010571,-.011064,
-.01,-.011464,
-.009368,-.011759,
-.008695,-.011939,
-.008,-.012,
.008,-.012,
.008695,-.011939,
.009368,-.011759,
.01,-.011464,
.010571,-.011064,
.011064,-.010571,
.011464,-.01,
.011759,-.009368,
.011939,-.008695,
.012,-.008,
.012,.008,
.011939,.008695,
.011759,.009368,
.011464,.01,
.011064,.010571,
.010571,.011064,
.01,.011464,
.009368,.011759,
.008695,.011939,
.008,.012,
0.0*
%
%ADD20MACRO20*%
%AMMACRO57*
4,1,40,-.013,-.017,
.013,-.017,
.013695,-.016939,
.014368,-.016759,
.015,-.016464,
.015571,-.016064,
.016064,-.015571,
.016464,-.015,
.016759,-.014368,
.016939,-.013695,
.017,-.013,
.017,.013,
.016939,.013695,
.016759,.014368,
.016464,.015,
.016064,.015571,
.015571,.016064,
.015,.016464,
.014368,.016759,
.013695,.016939,
.013,.017,
-.013,.017,
-.013695,.016939,
-.014368,.016759,
-.015,.016464,
-.015571,.016064,
-.016064,.015571,
-.016464,.015,
-.016759,.014368,
-.016939,.013695,
-.017,.013,
-.017,-.013,
-.016939,-.013695,
-.016759,-.014368,
-.016464,-.015,
-.016064,-.015571,
-.015571,-.016064,
-.015,-.016464,
-.014368,-.016759,
-.013695,-.016939,
-.013,-.017,
0.0*
%
%ADD57MACRO57*%
%AMMACRO67*
4,1,6,-.025,-.0135,
-.005,.0065,
-.005,.0135,
.005,.0135,
.005,.0065,
.025,-.0135,
-.025,-.0135,
0.0*
%
%ADD67MACRO67*%
%AMMACRO36*
4,1,40,-.017,.013,
-.017,-.013,
-.016939,-.013695,
-.016759,-.014368,
-.016464,-.015,
-.016064,-.015571,
-.015571,-.016064,
-.015,-.016464,
-.014368,-.016759,
-.013695,-.016939,
-.013,-.017,
.013,-.017,
.013695,-.016939,
.014368,-.016759,
.015,-.016464,
.015571,-.016064,
.016064,-.015571,
.016464,-.015,
.016759,-.014368,
.016939,-.013695,
.017,-.013,
.017,.013,
.016939,.013695,
.016759,.014368,
.016464,.015,
.016064,.015571,
.015571,.016064,
.015,.016464,
.014368,.016759,
.013695,.016939,
.013,.017,
-.013,.017,
-.013695,.016939,
-.014368,.016759,
-.015,.016464,
-.015571,.016064,
-.016064,.015571,
-.016464,.015,
-.016759,.014368,
-.016939,.013695,
-.017,.013,
0.0*
%
%ADD36MACRO36*%
%AMMACRO83*
4,1,6,-.0135,.005,
-.0065,.005,
.0135,.025,
.0135,-.025,
-.0065,-.005,
-.0135,-.005,
-.0135,.005,
0.0*
%
%ADD83MACRO83*%
%AMMACRO102*
4,1,20,.0655,-.1095,
.051,-.1095,
.051,-.12,
.0375,-.12,
.0375,-.1095,
-.0375,-.1095,
-.0375,-.12,
-.051,-.12,
-.051,-.1095,
-.0655,-.1095,
-.0655,.1095,
-.051,.1095,
-.051,.12,
-.0375,.12,
-.0375,.1095,
.0375,.1095,
.0375,.12,
.051,.12,
.051,.1095,
.0655,.1095,
.0655,-.1095,
0.0*
%
%ADD102MACRO102*%
%AMMACRO79*
4,1,20,-.1095,-.0655,
-.1095,-.051,
-.12,-.051,
-.12,-.0375,
-.1095,-.0375,
-.1095,.0375,
-.12,.0375,
-.12,.051,
-.1095,.051,
-.1095,.0655,
.1095,.0655,
.1095,.051,
.12,.051,
.12,.0375,
.1095,.0375,
.1095,-.0375,
.12,-.0375,
.12,-.051,
.1095,-.051,
.1095,-.0655,
-.1095,-.0655,
0.0*
%
%ADD79MACRO79*%
%AMMACRO22*
4,1,40,.011,-.007,
.011,.007,
.010939,.007695,
.010759,.008368,
.010464,.009,
.010064,.009571,
.009571,.010064,
.009,.010464,
.008368,.010759,
.007695,.010939,
.007,.011,
-.007,.011,
-.007695,.010939,
-.008368,.010759,
-.009,.010464,
-.009571,.010064,
-.010064,.009571,
-.010464,.009,
-.010759,.008368,
-.010939,.007695,
-.011,.007,
-.011,-.007,
-.010939,-.007695,
-.010759,-.008368,
-.010464,-.009,
-.010064,-.009571,
-.009571,-.010064,
-.009,-.010464,
-.008368,-.010759,
-.007695,-.010939,
-.007,-.011,
.007,-.011,
.007695,-.010939,
.008368,-.010759,
.009,-.010464,
.009571,-.010064,
.010064,-.009571,
.010464,-.009,
.010759,-.008368,
.010939,-.007695,
.011,-.007,
0.0*
%
%ADD22MACRO22*%
%AMMACRO14*
4,1,40,.007,.011,
-.007,.011,
-.007695,.010939,
-.008368,.010759,
-.009,.010464,
-.009571,.010064,
-.010064,.009571,
-.010464,.009,
-.010759,.008368,
-.010939,.007695,
-.011,.007,
-.011,-.007,
-.010939,-.007695,
-.010759,-.008368,
-.010464,-.009,
-.010064,-.009571,
-.009571,-.010064,
-.009,-.010464,
-.008368,-.010759,
-.007695,-.010939,
-.007,-.011,
.007,-.011,
.007695,-.010939,
.008368,-.010759,
.009,-.010464,
.009571,-.010064,
.010064,-.009571,
.010464,-.009,
.010759,-.008368,
.010939,-.007695,
.011,-.007,
.011,.007,
.010939,.007695,
.010759,.008368,
.010464,.009,
.010064,.009571,
.009571,.010064,
.009,.010464,
.008368,.010759,
.007695,.010939,
.007,.011,
0.0*
%
%ADD14MACRO14*%
%AMMACRO46*
4,1,40,-.012,.008,
-.012,-.008,
-.011939,-.008695,
-.011759,-.009368,
-.011464,-.01,
-.011064,-.010571,
-.010571,-.011064,
-.01,-.011464,
-.009368,-.011759,
-.008695,-.011939,
-.008,-.012,
.008,-.012,
.008695,-.011939,
.009368,-.011759,
.01,-.011464,
.010571,-.011064,
.011064,-.010571,
.011464,-.01,
.011759,-.009368,
.011939,-.008695,
.012,-.008,
.012,.008,
.011939,.008695,
.011759,.009368,
.011464,.01,
.011064,.010571,
.010571,.011064,
.01,.011464,
.009368,.011759,
.008695,.011939,
.008,.012,
-.008,.012,
-.008695,.011939,
-.009368,.011759,
-.01,.011464,
-.010571,.011064,
-.011064,.010571,
-.011464,.01,
-.011759,.009368,
-.011939,.008695,
-.012,.008,
0.0*
%
%ADD46MACRO46*%
%AMMACRO19*
4,1,40,.008,.012,
-.008,.012,
-.008695,.011939,
-.009368,.011759,
-.01,.011464,
-.010571,.011064,
-.011064,.010571,
-.011464,.01,
-.011759,.009368,
-.011939,.008695,
-.012,.008,
-.012,-.008,
-.011939,-.008695,
-.011759,-.009368,
-.011464,-.01,
-.011064,-.010571,
-.010571,-.011064,
-.01,-.011464,
-.009368,-.011759,
-.008695,-.011939,
-.008,-.012,
.008,-.012,
.008695,-.011939,
.009368,-.011759,
.01,-.011464,
.010571,-.011064,
.011064,-.010571,
.011464,-.01,
.011759,-.009368,
.011939,-.008695,
.012,-.008,
.012,.008,
.011939,.008695,
.011759,.009368,
.011464,.01,
.011064,.010571,
.010571,.011064,
.01,.011464,
.009368,.011759,
.008695,.011939,
.008,.012,
0.0*
%
%ADD19MACRO19*%
%AMMACRO58*
4,1,40,-.013,-.017,
.013,-.017,
.013695,-.016939,
.014368,-.016759,
.015,-.016464,
.015571,-.016064,
.016064,-.015571,
.016464,-.015,
.016759,-.014368,
.016939,-.013695,
.017,-.013,
.017,.013,
.016939,.013695,
.016759,.014368,
.016464,.015,
.016064,.015571,
.015571,.016064,
.015,.016464,
.014368,.016759,
.013695,.016939,
.013,.017,
-.013,.017,
-.013695,.016939,
-.014368,.016759,
-.015,.016464,
-.015571,.016064,
-.016064,.015571,
-.016464,.015,
-.016759,.014368,
-.016939,.013695,
-.017,.013,
-.017,-.013,
-.016939,-.013695,
-.016759,-.014368,
-.016464,-.015,
-.016064,-.015571,
-.015571,-.016064,
-.015,-.016464,
-.014368,-.016759,
-.013695,-.016939,
-.013,-.017,
0.0*
%
%ADD58MACRO58*%
%AMMACRO37*
4,1,40,-.017,.013,
-.017,-.013,
-.016939,-.013695,
-.016759,-.014368,
-.016464,-.015,
-.016064,-.015571,
-.015571,-.016064,
-.015,-.016464,
-.014368,-.016759,
-.013695,-.016939,
-.013,-.017,
.013,-.017,
.013695,-.016939,
.014368,-.016759,
.015,-.016464,
.015571,-.016064,
.016064,-.015571,
.016464,-.015,
.016759,-.014368,
.016939,-.013695,
.017,-.013,
.017,.013,
.016939,.013695,
.016759,.014368,
.016464,.015,
.016064,.015571,
.015571,.016064,
.015,.016464,
.014368,.016759,
.013695,.016939,
.013,.017,
-.013,.017,
-.013695,.016939,
-.014368,.016759,
-.015,.016464,
-.015571,.016064,
-.016064,.015571,
-.016464,.015,
-.016759,.014368,
-.016939,.013695,
-.017,.013,
0.0*
%
%ADD37MACRO37*%
%ADD71R,.001X.001*%
%ADD65R,.126X.201*%
%AMMACRO92*
4,1,42,-.00768,.00246,
-.00602,-.00537,
-.005913,-.005702,
-.005755,-.006013,
-.005545,-.006291,
-.00529,-.006529,
-.004997,-.006719,
-.004676,-.006855,
-.004336,-.006933,
-.003988,-.006951,
-.003642,-.006908,
-.00364,-.00691,
.00614,-.00483,
.006473,-.004727,
.006784,-.004568,
.007062,-.004358,
.007299,-.004103,
.007489,-.003811,
.007625,-.00349,
.007703,-.00315,
.007721,-.002802,
.00768,-.00246,
.00602,.00537,
.005913,.005702,
.005755,.006013,
.005545,.006291,
.00529,.006529,
.004997,.006719,
.004676,.006855,
.004336,.006933,
.003988,.006951,
.003642,.006908,
.00364,.00691,
-.00614,.00483,
-.006473,.004727,
-.006784,.004568,
-.007062,.004358,
-.007299,.004103,
-.007489,.003811,
-.007625,.00349,
-.007703,.00315,
-.007721,.002802,
-.00768,.00246,
0.0*
%
%ADD92MACRO92*%
%ADD99R,.06X.012*%
%ADD96R,.022X.04*%
%ADD43R,.042X.012*%
%ADD41R,.012X.042*%
%ADD118R,.06X.014*%
%ADD112R,.014X.033*%
%ADD111R,.033X.014*%
%ADD103R,.044X.012*%
%ADD115R,.014X.042*%
%ADD114R,.042X.014*%
%ADD80R,.012X.044*%
%ADD50R,.014X.06*%
%ADD42R,.036X.012*%
%ADD40R,.012X.036*%
%ADD29R,.045X.03*%
%ADD69R,.012X.036*%
%ADD68R,.036X.012*%
%ADD95R,.115X.138*%
%AMMACRO93*
4,1,40,.007,-.004,
.007,.004,
.00697,.004347,
.006879,.004684,
.006732,.005,
.006532,.005286,
.006286,.005532,
.006,.005732,
.005684,.005879,
.005347,.00597,
.005,.006,
-.005,.006,
-.005347,.00597,
-.005684,.005879,
-.006,.005732,
-.006286,.005532,
-.006532,.005286,
-.006732,.005,
-.006879,.004684,
-.00697,.004347,
-.007,.004,
-.007,-.004,
-.00697,-.004347,
-.006879,-.004684,
-.006732,-.005,
-.006532,-.005286,
-.006286,-.005532,
-.006,-.005732,
-.005684,-.005879,
-.005347,-.00597,
-.005,-.006,
.005,-.006,
.005347,-.00597,
.005684,-.005879,
.006,-.005732,
.006286,-.005532,
.006532,-.005286,
.006732,-.005,
.006879,-.004684,
.00697,-.004347,
.007,-.004,
0.0*
%
%ADD93MACRO93*%
%AMMACRO91*
4,1,40,-.004,-.007,
.004,-.007,
.004347,-.00697,
.004684,-.006879,
.005,-.006732,
.005286,-.006532,
.005532,-.006286,
.005732,-.006,
.005879,-.005684,
.00597,-.005347,
.006,-.005,
.006,.005,
.00597,.005347,
.005879,.005684,
.005732,.006,
.005532,.006286,
.005286,.006532,
.005,.006732,
.004684,.006879,
.004347,.00697,
.004,.007,
-.004,.007,
-.004347,.00697,
-.004684,.006879,
-.005,.006732,
-.005286,.006532,
-.005532,.006286,
-.005732,.006,
-.005879,.005684,
-.00597,.005347,
-.006,.005,
-.006,-.005,
-.00597,-.005347,
-.005879,-.005684,
-.005732,-.006,
-.005532,-.006286,
-.005286,-.006532,
-.005,-.006732,
-.004684,-.006879,
-.004347,-.00697,
-.004,-.007,
0.0*
%
%ADD91MACRO91*%
%ADD23R,.03X.064*%
%ADD81R,.138X.115*%
%ADD107R,.108X.138*%
%ADD106R,.05X.065*%
%ADD64R,.054X.025*%
%ADD82R,.065X.05*%
%ADD98R,.029X.043*%
%ADD48R,.065X.025*%
%ADD30R,.045X.09*%
%ADD87R,.043X.029*%
%ADD51R,.048X.016*%
%ADD27R,.045X.055*%
%ADD109R,.096X.014*%
%ADD73R,.016X.048*%
%ADD26R,.055X.045*%
%ADD24R,.197X.205*%
%ADD116R,.06X.095*%
%ADD72R,.054X.075*%
%ADD59R,.054X.074*%
%AMMACRO54*
4,1,25,-.26575,.30715,
-.209725,.333219,
-.150024,.349164,
-.088461,.3545,
-.026908,.349064,
.032767,.333022,
.08875,.306861,
.139339,.271377,
.182998,.227647,
.2184,.177,
.244469,.120975,
.260414,.061274,
.26575,-.000289,
.260314,-.061842,
.244272,-.121517,
.218111,-.1775,
.182627,-.228089,
.138897,-.271748,
.08825,-.30715,
.032225,-.333219,
-.027476,-.349164,
-.089039,-.3545,
-.150592,-.349064,
-.210267,-.333022,
-.26575,-.30715,
-.26575,.30715,
0.0*
%
%ADD54MACRO54*%
%AMMACRO117*
4,1,25,.26575,.30715,
.209725,.333219,
.150024,.349164,
.088461,.3545,
.026908,.349064,
-.032767,.333022,
-.08875,.306861,
-.139339,.271377,
-.182998,.227647,
-.2184,.177,
-.244469,.120975,
-.260414,.061274,
-.26575,-.000289,
-.260314,-.061842,
-.244272,-.121517,
-.218111,-.1775,
-.182627,-.228089,
-.138897,-.271748,
-.08825,-.30715,
-.032225,-.333219,
.027476,-.349164,
.089039,-.3545,
.150592,-.349064,
.210267,-.333022,
.26575,-.30715,
.26575,.30715,
0.0*
%
%ADD117MACRO117*%
%ADD75R,.09X.095*%
%AMMACRO88*
4,1,40,-.0225,.007,
-.022378,.008389,
-.022018,.009736,
-.021428,.011,
-.020628,.012142,
-.019642,.013128,
-.0185,.013928,
-.017236,.014518,
-.015889,.014878,
-.0145,.015,
.0145,.015,
.015889,.014878,
.017236,.014518,
.0185,.013928,
.019642,.013128,
.020628,.012142,
.021428,.011,
.022018,.009736,
.022378,.008389,
.0225,.007,
.0225,-.007,
.022378,-.008389,
.022018,-.009736,
.021428,-.011,
.020628,-.012142,
.019642,-.013128,
.0185,-.013928,
.017236,-.014518,
.015889,-.014878,
.0145,-.015,
-.0145,-.015,
-.015889,-.014878,
-.017236,-.014518,
-.0185,-.013928,
-.019642,-.013128,
-.020628,-.012142,
-.021428,-.011,
-.022018,-.009736,
-.022378,-.008389,
-.0225,-.007,
-.0225,.007,
0.0*
%
%ADD88MACRO88*%
%ADD85C,.375*%
%AMMACRO63*
4,1,40,-.008,.014,
.008,.014,
.008695,.013939,
.009368,.013759,
.01,.013464,
.010571,.013064,
.011064,.012571,
.011464,.012,
.011759,.011368,
.011939,.010695,
.012,.01,
.012,-.01,
.011939,-.010695,
.011759,-.011368,
.011464,-.012,
.011064,-.012571,
.010571,-.013064,
.01,-.013464,
.009368,-.013759,
.008695,-.013939,
.008,-.014,
-.008,-.014,
-.008695,-.013939,
-.009368,-.013759,
-.01,-.013464,
-.010571,-.013064,
-.011064,-.012571,
-.011464,-.012,
-.011759,-.011368,
-.011939,-.010695,
-.012,-.01,
-.012,.01,
-.011939,.010695,
-.011759,.011368,
-.011464,.012,
-.011064,.012571,
-.010571,.013064,
-.01,.013464,
-.009368,.013759,
-.008695,.013939,
-.008,.014,
0.0*
%
%ADD63MACRO63*%
%AMMACRO28*
4,1,40,.007,.0225,
.008389,.022378,
.009736,.022018,
.011,.021428,
.012142,.020628,
.013128,.019642,
.013928,.0185,
.014518,.017236,
.014878,.015889,
.015,.0145,
.015,-.0145,
.014878,-.015889,
.014518,-.017236,
.013928,-.0185,
.013128,-.019642,
.012142,-.020628,
.011,-.021428,
.009736,-.022018,
.008389,-.022378,
.007,-.0225,
-.007,-.0225,
-.008389,-.022378,
-.009736,-.022018,
-.011,-.021428,
-.012142,-.020628,
-.013128,-.019642,
-.013928,-.0185,
-.014518,-.017236,
-.014878,-.015889,
-.015,-.0145,
-.015,.0145,
-.014878,.015889,
-.014518,.017236,
-.013928,.0185,
-.013128,.019642,
-.012142,.020628,
-.011,.021428,
-.009736,.022018,
-.008389,.022378,
-.007,.0225,
.007,.0225,
0.0*
%
%ADD28MACRO28*%
%ADD25R,.045X.059*%
%ADD44R,.136X.136*%
%ADD119R,.272X.272*%
%ADD113R,.128X.128*%
%AMMACRO53*
4,1,40,-.008,-.012,
.008,-.012,
.008695,-.011939,
.009368,-.011759,
.01,-.011464,
.010571,-.011064,
.011064,-.010571,
.011464,-.01,
.011759,-.009368,
.011939,-.008695,
.012,-.008,
.012,.008,
.011939,.008695,
.011759,.009368,
.011464,.01,
.011064,.010571,
.010571,.011064,
.01,.011464,
.009368,.011759,
.008695,.011939,
.008,.012,
-.008,.012,
-.008695,.011939,
-.009368,.011759,
-.01,.011464,
-.010571,.011064,
-.011064,.010571,
-.011464,.01,
-.011759,.009368,
-.011939,.008695,
-.012,.008,
-.012,-.008,
-.011939,-.008695,
-.011759,-.009368,
-.011464,-.01,
-.011064,-.010571,
-.010571,-.011064,
-.01,-.011464,
-.009368,-.011759,
-.008695,-.011939,
-.008,-.012,
0.0*
%
%ADD53MACRO53*%
%AMMACRO18*
4,1,40,.012,-.008,
.012,.008,
.011939,.008695,
.011759,.009368,
.011464,.01,
.011064,.010571,
.010571,.011064,
.01,.011464,
.009368,.011759,
.008695,.011939,
.008,.012,
-.008,.012,
-.008695,.011939,
-.009368,.011759,
-.01,.011464,
-.010571,.011064,
-.011064,.010571,
-.011464,.01,
-.011759,.009368,
-.011939,.008695,
-.012,.008,
-.012,-.008,
-.011939,-.008695,
-.011759,-.009368,
-.011464,-.01,
-.011064,-.010571,
-.010571,-.011064,
-.01,-.011464,
-.009368,-.011759,
-.008695,-.011939,
-.008,-.012,
.008,-.012,
.008695,-.011939,
.009368,-.011759,
.01,-.011464,
.010571,-.011064,
.011064,-.010571,
.011464,-.01,
.011759,-.009368,
.011939,-.008695,
.012,-.008,
0.0*
%
%ADD18MACRO18*%
%AMMACRO15*
4,1,40,-.007,-.011,
.007,-.011,
.007695,-.010939,
.008368,-.010759,
.009,-.010464,
.009571,-.010064,
.010064,-.009571,
.010464,-.009,
.010759,-.008368,
.010939,-.007695,
.011,-.007,
.011,.007,
.010939,.007695,
.010759,.008368,
.010464,.009,
.010064,.009571,
.009571,.010064,
.009,.010464,
.008368,.010759,
.007695,.010939,
.007,.011,
-.007,.011,
-.007695,.010939,
-.008368,.010759,
-.009,.010464,
-.009571,.010064,
-.010064,.009571,
-.010464,.009,
-.010759,.008368,
-.010939,.007695,
-.011,.007,
-.011,-.007,
-.010939,-.007695,
-.010759,-.008368,
-.010464,-.009,
-.010064,-.009571,
-.009571,-.010064,
-.009,-.010464,
-.008368,-.010759,
-.007695,-.010939,
-.007,-.011,
0.0*
%
%ADD15MACRO15*%
%AMMACRO34*
4,1,40,-.011,.007,
-.011,-.007,
-.010939,-.007695,
-.010759,-.008368,
-.010464,-.009,
-.010064,-.009571,
-.009571,-.010064,
-.009,-.010464,
-.008368,-.010759,
-.007695,-.010939,
-.007,-.011,
.007,-.011,
.007695,-.010939,
.008368,-.010759,
.009,-.010464,
.009571,-.010064,
.010064,-.009571,
.010464,-.009,
.010759,-.008368,
.010939,-.007695,
.011,-.007,
.011,.007,
.010939,.007695,
.010759,.008368,
.010464,.009,
.010064,.009571,
.009571,.010064,
.009,.010464,
.008368,.010759,
.007695,.010939,
.007,.011,
-.007,.011,
-.007695,.010939,
-.008368,.010759,
-.009,.010464,
-.009571,.010064,
-.010064,.009571,
-.010464,.009,
-.010759,.008368,
-.010939,.007695,
-.011,.007,
0.0*
%
%ADD34MACRO34*%
%AMMACRO84*
4,1,6,-.0135,.025,
.0065,.005,
.0135,.005,
.0135,-.005,
.0065,-.005,
-.0135,-.025,
-.0135,.025,
0.0*
%
%ADD84MACRO84*%
%AMMACRO77*
4,1,40,.013,.017,
-.013,.017,
-.013695,.016939,
-.014368,.016759,
-.015,.016464,
-.015571,.016064,
-.016064,.015571,
-.016464,.015,
-.016759,.014368,
-.016939,.013695,
-.017,.013,
-.017,-.013,
-.016939,-.013695,
-.016759,-.014368,
-.016464,-.015,
-.016064,-.015571,
-.015571,-.016064,
-.015,-.016464,
-.014368,-.016759,
-.013695,-.016939,
-.013,-.017,
.013,-.017,
.013695,-.016939,
.014368,-.016759,
.015,-.016464,
.015571,-.016064,
.016064,-.015571,
.016464,-.015,
.016759,-.014368,
.016939,-.013695,
.017,-.013,
.017,.013,
.016939,.013695,
.016759,.014368,
.016464,.015,
.016064,.015571,
.015571,.016064,
.015,.016464,
.014368,.016759,
.013695,.016939,
.013,.017,
0.0*
%
%ADD77MACRO77*%
%AMMACRO38*
4,1,40,.017,-.013,
.017,.013,
.016939,.013695,
.016759,.014368,
.016464,.015,
.016064,.015571,
.015571,.016064,
.015,.016464,
.014368,.016759,
.013695,.016939,
.013,.017,
-.013,.017,
-.013695,.016939,
-.014368,.016759,
-.015,.016464,
-.015571,.016064,
-.016064,.015571,
-.016464,.015,
-.016759,.014368,
-.016939,.013695,
-.017,.013,
-.017,-.013,
-.016939,-.013695,
-.016759,-.014368,
-.016464,-.015,
-.016064,-.015571,
-.015571,-.016064,
-.015,-.016464,
-.014368,-.016759,
-.013695,-.016939,
-.013,-.017,
.013,-.017,
.013695,-.016939,
.014368,-.016759,
.015,-.016464,
.015571,-.016064,
.016064,-.015571,
.016464,-.015,
.016759,-.014368,
.016939,-.013695,
.017,-.013,
0.0*
%
%ADD38MACRO38*%
%AMMACRO66*
4,1,6,-.005,-.0135,
-.005,-.0065,
-.025,.0135,
.025,.0135,
.005,-.0065,
.005,-.0135,
-.005,-.0135,
0.0*
%
%ADD66MACRO66*%
%AMMACRO52*
4,1,40,-.008,-.012,
.008,-.012,
.008695,-.011939,
.009368,-.011759,
.01,-.011464,
.010571,-.011064,
.011064,-.010571,
.011464,-.01,
.011759,-.009368,
.011939,-.008695,
.012,-.008,
.012,.008,
.011939,.008695,
.011759,.009368,
.011464,.01,
.011064,.010571,
.010571,.011064,
.01,.011464,
.009368,.011759,
.008695,.011939,
.008,.012,
-.008,.012,
-.008695,.011939,
-.009368,.011759,
-.01,.011464,
-.010571,.011064,
-.011064,.010571,
-.011464,.01,
-.011759,.009368,
-.011939,.008695,
-.012,.008,
-.012,-.008,
-.011939,-.008695,
-.011759,-.009368,
-.011464,-.01,
-.011064,-.010571,
-.010571,-.011064,
-.01,-.011464,
-.009368,-.011759,
-.008695,-.011939,
-.008,-.012,
0.0*
%
%ADD52MACRO52*%
%AMMACRO17*
4,1,40,.012,-.008,
.012,.008,
.011939,.008695,
.011759,.009368,
.011464,.01,
.011064,.010571,
.010571,.011064,
.01,.011464,
.009368,.011759,
.008695,.011939,
.008,.012,
-.008,.012,
-.008695,.011939,
-.009368,.011759,
-.01,.011464,
-.010571,.011064,
-.011064,.010571,
-.011464,.01,
-.011759,.009368,
-.011939,.008695,
-.012,.008,
-.012,-.008,
-.011939,-.008695,
-.011759,-.009368,
-.011464,-.01,
-.011064,-.010571,
-.010571,-.011064,
-.01,-.011464,
-.009368,-.011759,
-.008695,-.011939,
-.008,-.012,
.008,-.012,
.008695,-.011939,
.009368,-.011759,
.01,-.011464,
.010571,-.011064,
.011064,-.010571,
.011464,-.01,
.011759,-.009368,
.011939,-.008695,
.012,-.008,
0.0*
%
%ADD17MACRO17*%
%AMMACRO16*
4,1,40,-.007,-.011,
.007,-.011,
.007695,-.010939,
.008368,-.010759,
.009,-.010464,
.009571,-.010064,
.010064,-.009571,
.010464,-.009,
.010759,-.008368,
.010939,-.007695,
.011,-.007,
.011,.007,
.010939,.007695,
.010759,.008368,
.010464,.009,
.010064,.009571,
.009571,.010064,
.009,.010464,
.008368,.010759,
.007695,.010939,
.007,.011,
-.007,.011,
-.007695,.010939,
-.008368,.010759,
-.009,.010464,
-.009571,.010064,
-.010064,.009571,
-.010464,.009,
-.010759,.008368,
-.010939,.007695,
-.011,.007,
-.011,-.007,
-.010939,-.007695,
-.010759,-.008368,
-.010464,-.009,
-.010064,-.009571,
-.009571,-.010064,
-.009,-.010464,
-.008368,-.010759,
-.007695,-.010939,
-.007,-.011,
0.0*
%
%ADD16MACRO16*%
%AMMACRO35*
4,1,40,-.011,.007,
-.011,-.007,
-.010939,-.007695,
-.010759,-.008368,
-.010464,-.009,
-.010064,-.009571,
-.009571,-.010064,
-.009,-.010464,
-.008368,-.010759,
-.007695,-.010939,
-.007,-.011,
.007,-.011,
.007695,-.010939,
.008368,-.010759,
.009,-.010464,
.009571,-.010064,
.010064,-.009571,
.010464,-.009,
.010759,-.008368,
.010939,-.007695,
.011,-.007,
.011,.007,
.010939,.007695,
.010759,.008368,
.010464,.009,
.010064,.009571,
.009571,.010064,
.009,.010464,
.008368,.010759,
.007695,.010939,
.007,.011,
-.007,.011,
-.007695,.010939,
-.008368,.010759,
-.009,.010464,
-.009571,.010064,
-.010064,.009571,
-.010464,.009,
-.010759,.008368,
-.010939,.007695,
-.011,.007,
0.0*
%
%ADD35MACRO35*%
%ADD120C,.012*%
%ADD121C,.015*%
%ADD122C,.038*%
%ADD123C,.039*%
%ADD124C,.004*%
%ADD125C,.006*%
%ADD126C,.005*%
%ADD127C,.0035*%
%ADD128C,.00413*%
%ADD129C,.008*%
%ADD130C,.0055*%
%ADD131C,.0049*%
%ADD132C,.00575*%
%ADD134R,.008X.019*%
%ADD135C,.04404*%
%ADD133R,.008X.008*%
G75*
%LPD*%
G75*
G36*
G01X443151Y493059D02*
X476035Y498319D01*
G03X495140Y520723I-3584J22404D01*
G01Y562992D01*
G02X500010Y567862I4870J0D01*
G01X818898D01*
G02X823768Y562992I0J-4870D01*
G01Y7874D01*
G02X818898Y3004I-4870J0D01*
G01X168082D01*
Y8000D01*
X344155D01*
G03X347185I1515J2237D01*
G01X358328D01*
G03X361358I1515J2237D01*
G01X372501D01*
G03X375531I1515J2237D01*
G01X386674D01*
G03X389704I1515J2237D01*
G01X400848D01*
G03X403878I1515J2237D01*
G01X415021D01*
G03X418051I1515J2237D01*
G01X429194D01*
G03X432224I1515J2237D01*
G01X443367D01*
G03X446397I1515J2237D01*
G01X457540D01*
G03X460570I1515J2237D01*
G01X471714D01*
G03X474744I1515J2237D01*
G01X485887D01*
G03X488917I1515J2237D01*
G01X500060D01*
G03X503090I1515J2237D01*
G01X514233D01*
G03X517263I1515J2237D01*
G01X528407D01*
G03X531437I1515J2237D01*
G01X542580D01*
G03X545610I1515J2237D01*
G01X556753D01*
G03X559783I1515J2237D01*
G01X570926D01*
G03X573956I1515J2237D01*
G01X585099D01*
G03X588129I1515J2237D01*
G01X714233D01*
G03X717263I1515J2237D01*
G01X728406D01*
G03X731436I1515J2237D01*
G01X742579D01*
G03X745609I1515J2237D01*
G01X756752D01*
G03X759782I1515J2237D01*
G01X818772D01*
Y562866D01*
X500136D01*
Y520723D01*
G02X476824Y493386I-27685J1D01*
G01X443548Y488063D01*
X383223D01*
X349967Y493383D01*
G02X326656Y520719I4374J27337D01*
G01Y563116D01*
X7896D01*
X7750Y562970D01*
Y562762D01*
X7896Y562616D01*
X8000D01*
Y8000D01*
X102990D01*
Y3004D01*
X7874D01*
G02X3004Y7874I0J4870D01*
G01Y562992D01*
G02X7874Y567862I4870J0D01*
G01X326783D01*
G02X331650Y563117I-1J-4870D01*
G01Y562616D01*
X331652D01*
Y520719D01*
G03X350756Y498316I22689J1D01*
G01X383620Y493059D01*
X443151D01*
G37*
G36*
G01X121240Y107000D02*
X72700D01*
X70100Y109600D01*
Y123800D01*
X70600Y124300D01*
X80900D01*
X84200Y121000D01*
X119700D01*
X119725Y120975D01*
X119750Y121000D01*
X121210D01*
X122450Y119760D01*
Y108210D01*
X121240Y107000D01*
G37*
G36*
G01X26599Y107090D02*
X25417Y108272D01*
Y137317D01*
X26046Y137946D01*
X26049D01*
X26339Y138236D01*
X31498D01*
Y138098D01*
X51902D01*
Y138236D01*
X60248D01*
Y137948D01*
X62248D01*
Y137952D01*
X62688Y137512D01*
Y126812D01*
X62700Y126801D01*
Y108440D01*
X61350Y107090D01*
X26599D01*
G37*
G36*
G01X35556Y139731D02*
X35604Y139680D01*
X35501Y139438D01*
X26100D01*
X25275Y140263D01*
Y153258D01*
X26085Y154068D01*
X35432D01*
X35556Y153945D01*
Y139731D01*
G37*
G36*
G01X46200Y199406D02*
X41250Y194456D01*
X41135Y194492D01*
G03X38709Y193944I-735J-2392D01*
G01X37182D01*
X37174Y193945D01*
G03X37049Y193950I-126J-1597D01*
G01X35449D01*
G03X35324Y193945I1J-1602D01*
G01X35316Y193944D01*
X33582D01*
X33574Y193945D01*
G03X33449Y193950I-126J-1597D01*
G01X31849D01*
G03X31724Y193945I1J-1602D01*
G01X31716Y193944D01*
X27769D01*
X26087Y192262D01*
Y178568D01*
X28654Y176001D01*
Y169083D01*
X28164Y168593D01*
X20306D01*
X19819Y169080D01*
Y197544D01*
X22488Y200212D01*
X39512D01*
X42675Y203375D01*
X46625D01*
X46798Y203202D01*
Y201738D01*
X46200Y201140D01*
Y199406D01*
G37*
G36*
G01X30457Y156765D02*
X30091Y157131D01*
Y173943D01*
X30718Y174570D01*
X35343D01*
X36579Y173334D01*
Y163892D01*
X35837Y163150D01*
Y162896D01*
X35556Y162615D01*
Y156765D01*
X30457D01*
G37*
G36*
G01X84700Y123000D02*
X81700Y126000D01*
X65200D01*
X63890Y127310D01*
Y137690D01*
X64149Y137948D01*
X66152D01*
Y137976D01*
X69676D01*
X70200Y138500D01*
X80200D01*
X82700Y141000D01*
Y147500D01*
X83700Y148500D01*
X120200D01*
X121200Y147500D01*
Y124000D01*
X120200Y123000D01*
X84700D01*
G37*
G36*
G01X37514Y139438D02*
X37226Y139725D01*
X36902Y140063D01*
Y146902D01*
X36757D01*
Y148248D01*
X36952D01*
Y155152D01*
X36757D01*
Y155848D01*
X36952D01*
Y162312D01*
X37740Y163100D01*
X50781D01*
X54000Y159881D01*
Y140500D01*
X52938Y139438D01*
X37514D01*
G37*
G36*
G01X22165Y159091D02*
X21521Y159735D01*
Y166096D01*
X22029Y166604D01*
X28467D01*
X28703Y166368D01*
Y166320D01*
G03X28698Y166200I1597J-127D01*
G01Y164800D01*
G03X28703Y164687I1601J14D01*
G01Y159436D01*
X28358Y159091D01*
X27483D01*
X27473Y159092D01*
G03X27300Y159102I-179J-1592D01*
G01X25700D01*
G03X25527Y159092I6J-1602D01*
G01X25517Y159091D01*
X22165D01*
G37*
G36*
G01X60200Y203350D02*
X49100D01*
X48600Y203850D01*
Y215600D01*
X49000Y216000D01*
X60450D01*
X60950Y215500D01*
Y204100D01*
X60200Y203350D01*
G37*
G36*
G01X23300Y209300D02*
X22560Y210040D01*
Y212240D01*
X23670Y213350D01*
X32050D01*
X32500Y212900D01*
Y212765D01*
G03X32498Y212700I1599J-82D01*
G01Y211100D01*
G03X32500Y211035I1601J17D01*
G01Y210000D01*
X31800Y209300D01*
X30665D01*
G03X30600Y209302I-82J-1599D01*
G01X29200D01*
G03X29135Y209300I17J-1601D01*
G01X26665D01*
G03X26600Y209302I-82J-1599D01*
G01X25200D01*
G03X25135Y209300I17J-1601D01*
G01X23300D01*
G37*
G36*
G01X38828Y268208D02*
X30945D01*
X29563Y269590D01*
Y276326D01*
X29791Y276554D01*
X35119D01*
X37311Y278746D01*
X45751D01*
X45896Y278600D01*
Y275275D01*
X38828Y268208D01*
G37*
G36*
G01X76498Y312651D02*
X76087Y313062D01*
X76095Y313156D01*
G03X76102Y313300I-1595J150D01*
G01Y314700D01*
G03X76063Y315050I-1602J-1D01*
G01X76058Y315071D01*
Y315440D01*
X74217Y317281D01*
Y323092D01*
X74461Y323336D01*
X79321D01*
X79859Y322798D01*
Y312896D01*
X79614Y312651D01*
X76498D01*
G37*
G36*
G01X67500Y316800D02*
X66800Y317500D01*
X59200D01*
X58800Y317900D01*
Y322000D01*
X59300Y322500D01*
X71900D01*
X72600Y321800D01*
Y317100D01*
X72300Y316800D01*
X67500D01*
G37*
G36*
G01X135500Y163000D02*
X125900D01*
X125850Y163050D01*
X123150D01*
X120500Y165700D01*
Y186750D01*
X121600Y187850D01*
X135250D01*
X136300Y186800D01*
Y163800D01*
X135500Y163000D01*
G37*
G36*
G01X172400Y171500D02*
X140100D01*
X138100Y173500D01*
Y194500D01*
X138600Y195000D01*
X186400D01*
X188900Y192500D01*
Y183500D01*
X188400Y183000D01*
X176500D01*
X173400Y179900D01*
Y172500D01*
X172400Y171500D01*
G37*
G36*
G01X191451Y159394D02*
X190400Y160445D01*
Y193312D01*
X186712Y197000D01*
X138600D01*
X138000Y197600D01*
Y209400D01*
X140745Y212145D01*
X201748D01*
X202293Y211600D01*
Y210823D01*
G03X202292Y210785I1600J-61D01*
G01Y209185D01*
G03X202293Y209147I1601J23D01*
G01Y208299D01*
X203900Y206692D01*
Y160301D01*
X202993Y159394D01*
X191451D01*
G37*
G36*
G01X92190Y445940D02*
X91050Y447080D01*
Y469150D01*
X91350Y469450D01*
X96700D01*
X97050Y469100D01*
Y453515D01*
G03X97048Y453450I1599J-82D01*
G01Y451850D01*
G03X97050Y451785I1601J17D01*
G01Y448890D01*
X97220Y448720D01*
Y446180D01*
X96980Y445940D01*
X92190D01*
G37*
G36*
G01X175200Y128400D02*
X174750Y128850D01*
Y134300D01*
X175054Y134604D01*
X176648D01*
Y134700D01*
X178952D01*
Y134604D01*
X180596D01*
X180850Y134350D01*
Y128750D01*
X180500Y128400D01*
X175200D01*
G37*
G36*
G01X172900Y159000D02*
X149900D01*
X148900Y160000D01*
Y169000D01*
X149400Y169500D01*
X172900D01*
X173400Y169000D01*
Y159500D01*
X172900Y159000D01*
G37*
G36*
G01X186700Y134300D02*
X182800D01*
X182600Y134500D01*
Y138900D01*
X183200Y139500D01*
X185400D01*
X187600Y141700D01*
Y147600D01*
X188400Y148400D01*
X195800D01*
X196600Y147600D01*
Y139300D01*
X196100Y138800D01*
X191200D01*
X186700Y134300D01*
G37*
G36*
G01X198615Y347958D02*
X198562Y348010D01*
X197340D01*
X196538Y348812D01*
Y356639D01*
X197500Y357601D01*
X246618D01*
X246736Y357719D01*
X251406D01*
X253121Y359434D01*
X255280D01*
X256106Y358608D01*
Y352511D01*
X251553Y347958D01*
X232610D01*
X232597Y348145D01*
G03X228203I-2197J-145D01*
G01X228190Y347958D01*
X198615D01*
G37*
G36*
G01X202000Y447000D02*
X199000Y450000D01*
Y484000D01*
X200400Y485400D01*
X219100D01*
X219398Y485101D01*
Y448849D01*
X217550Y447000D01*
X202000D01*
G37*
G36*
G01X257413Y50650D02*
X256401Y51662D01*
Y58996D01*
X257094Y59688D01*
X261102D01*
G03X261881Y59915I0J1452D01*
G01X264170D01*
X264786Y59299D01*
Y51496D01*
X263940Y50650D01*
X257413D01*
G37*
G36*
G01X238571Y128250D02*
X225000D01*
X221150Y132100D01*
Y159550D01*
X222200Y160600D01*
X241055D01*
X242920Y158735D01*
Y132599D01*
X238571Y128250D01*
G37*
G36*
G01X252269Y129484D02*
X245136Y136617D01*
Y202237D01*
X245202Y202302D01*
Y246895D01*
X245136Y246960D01*
Y249224D01*
X248213Y252301D01*
X275423D01*
X277021Y250703D01*
Y132027D01*
X274478Y129484D01*
X252269D01*
G37*
G36*
G01X230700Y173000D02*
X217200D01*
X214650Y175550D01*
Y177350D01*
X213500Y178500D01*
X206400D01*
X205400Y179500D01*
Y199800D01*
X206950Y201350D01*
X214150D01*
X217300Y198200D01*
X229600D01*
X232400Y195400D01*
Y174700D01*
X230700Y173000D01*
G37*
G36*
G01X241600Y200400D02*
X222350D01*
X219150Y203600D01*
Y245697D01*
X222050Y248597D01*
X241800D01*
X244000Y246397D01*
Y202800D01*
X241600Y200400D01*
G37*
G36*
G01X227300Y280300D02*
X225652Y281949D01*
Y285251D01*
X225999Y285598D01*
X227300D01*
G03X227365Y285600I-17J1601D01*
G01X229935D01*
G03X230000Y285598I82J1599D01*
G01X230999D01*
X231900Y284697D01*
Y280900D01*
X231300Y280300D01*
X227300D01*
G37*
G36*
G01X220500Y359000D02*
X220000Y359500D01*
Y386500D01*
X221500Y388000D01*
X228297D01*
X231947Y391650D01*
Y401449D01*
X232498Y402000D01*
X265409D01*
X266120Y401288D01*
X268120D01*
G03X268638Y400862I1834J1702D01*
G01X269500Y400000D01*
Y391000D01*
X267930Y389430D01*
X234050D01*
X232000Y387380D01*
Y359500D01*
X231500Y359000D01*
X220500D01*
G37*
G36*
G01X234000D02*
X233500Y359500D01*
Y387000D01*
X234500Y388000D01*
X239718D01*
Y387918D01*
X251082D01*
X252000Y387000D01*
Y361500D01*
X249500Y359000D01*
X234000D01*
G37*
G36*
G01X231200Y403500D02*
X227700Y407000D01*
X227065D01*
G03X227000Y407002I-82J-1599D01*
G01X225400D01*
G03X225335Y407000I17J-1601D01*
G01X224800D01*
X224500Y407300D01*
Y421100D01*
X226481Y423081D01*
X250990D01*
X252000Y422071D01*
Y404000D01*
X251500Y403500D01*
X231200D01*
G37*
G36*
G01X222237Y433463D02*
X220600Y435100D01*
Y483135D01*
G03X220602Y483200I-1599J82D01*
G01Y484800D01*
G03X220600Y484865I-1601J-17D01*
G01Y485000D01*
X220800Y485200D01*
X249800D01*
X251100Y483900D01*
Y436100D01*
X248463Y433463D01*
X222237D01*
G37*
G36*
G01X250300Y486800D02*
X207700D01*
X206400Y488100D01*
Y503900D01*
X209500Y507000D01*
X247000D01*
X250800Y503200D01*
Y487300D01*
X250300Y486800D01*
G37*
G36*
G01X280961Y50115D02*
X280161Y50915D01*
Y57815D01*
X280661Y58315D01*
X286511D01*
X288136Y56690D01*
X288562D01*
X288598Y56675D01*
G03X288708Y56636I557J1395D01*
G01X288755Y56621D01*
X290161Y55215D01*
Y50515D01*
X289761Y50115D01*
X280961D01*
G37*
G36*
G01X286661Y73465D02*
X286561Y73365D01*
X280311D01*
X280211Y73465D01*
Y78915D01*
X280611Y79315D01*
X286261D01*
X286661Y78915D01*
Y73465D01*
G37*
G36*
G01X279500Y138500D02*
X278500Y139500D01*
Y247500D01*
X279000Y248000D01*
X282000D01*
X285800Y244200D01*
X286602D01*
X286603Y244198D01*
X297998D01*
X297999Y244200D01*
X309600D01*
X310400Y243400D01*
Y143400D01*
X309000Y142000D01*
X285500D01*
X282000Y138500D01*
X279500D01*
G37*
G36*
G01X280000Y114250D02*
X279900Y114350D01*
Y133750D01*
X286050Y139900D01*
X286100D01*
X286700Y140500D01*
X297893D01*
X298409Y139984D01*
Y130213D01*
X298350Y130154D01*
Y126150D01*
X286450Y114250D01*
X280000D01*
G37*
G36*
G01X287101Y245400D02*
X284500Y248001D01*
Y255838D01*
X285375Y256712D01*
X297462D01*
X298705Y255470D01*
Y246605D01*
X297500Y245400D01*
X287101D01*
G37*
G36*
G01X324654Y258152D02*
X318148D01*
X317850Y258450D01*
Y262450D01*
X318500Y263100D01*
X325300D01*
X325430Y262970D01*
Y258928D01*
X324654Y258152D01*
G37*
G36*
G01X266961Y280650D02*
X266302Y281309D01*
Y285102D01*
X266700Y285500D01*
X272300D01*
X273200Y284600D01*
Y280900D01*
X272950Y280650D01*
X266961D01*
G37*
G36*
G01X277420Y372000D02*
X277089Y372331D01*
Y375340D01*
X276396Y376033D01*
X273989D01*
X273005Y377017D01*
Y386997D01*
X272500Y387502D01*
Y399000D01*
X273000Y399500D01*
X277738D01*
X277770Y399489D01*
G03X278300Y399398I532J1511D01*
G01X279700D01*
G03X280230Y399489I-2J1602D01*
G01X280262Y399500D01*
X282000D01*
X282500Y399000D01*
Y372500D01*
X282000Y372000D01*
X277420D01*
G37*
G36*
G01X369106Y219553D02*
X354293Y204740D01*
X331636D01*
X329336Y207040D01*
Y221644D01*
X332719Y225027D01*
X356953D01*
X362225Y230299D01*
X362227Y230301D01*
G03X362306Y230380I-1517J1596D01*
G01X362308Y230382D01*
X362526Y230600D01*
X382601D01*
X383353Y229848D01*
X390501D01*
X391253Y230600D01*
X396059D01*
X396459Y230200D01*
Y229705D01*
X394209Y227455D01*
X392705D01*
G03X391732Y227830I-974J-1077D01*
G01X362877D01*
X362502Y227455D01*
X362455D01*
X354540Y219540D01*
X345997D01*
X345297Y220240D01*
Y222040D01*
X345197Y222140D01*
X332997D01*
X332097Y221240D01*
Y210140D01*
X334897Y207340D01*
X337798D01*
X338002Y207136D01*
X343457D01*
X343625Y207304D01*
X343733Y207279D01*
G03X344091Y207238I360J1561D01*
G01X345691D01*
G03X346221Y207329I-2J1602D01*
G01X346253Y207340D01*
X347832D01*
G03X347897Y207338I82J1599D01*
G01X349297D01*
G03X349362Y207340I-17J1601D01*
G01X349700D01*
X349769Y207409D01*
X349813Y207424D01*
G03X350813Y208424I-516J1516D01*
G01X350828Y208468D01*
X364582Y222222D01*
X389954D01*
X390659Y222926D01*
X394270D01*
X394712Y223368D01*
X396061D01*
X396459Y222970D01*
Y221903D01*
X394109Y219553D01*
X392662D01*
G03X390802I-930J-1049D01*
G01X369106D01*
G37*
G36*
G01X345446Y277000D02*
X345409Y277015D01*
G03X344850Y277128I-561J-1338D01*
G01X341872D01*
X341500Y277500D01*
Y282000D01*
X342500Y283000D01*
X348398D01*
X349216Y282182D01*
Y277597D01*
X348619Y277000D01*
X345446D01*
G37*
G36*
G01X331982Y418900D02*
Y419007D01*
X331600Y419390D01*
Y425100D01*
X331798Y425298D01*
X339402D01*
X339900Y424800D01*
Y419400D01*
X339400Y418900D01*
X331982D01*
G37*
G36*
G01X449900Y343100D02*
X449601Y343399D01*
Y343483D01*
G03X449602Y343500I-1596J102D01*
G01Y344900D01*
G03X449600Y344965I-1601J-17D01*
G01Y346500D01*
X448239Y347861D01*
Y353681D01*
X457458Y362900D01*
X471050D01*
X471950Y362000D01*
Y360456D01*
G03X471496Y359338I1147J-1117D01*
G01Y357938D01*
G03X471950Y356820I1601J-1D01*
G01Y353838D01*
X471450Y353338D01*
X468734D01*
X467977Y354095D01*
X463874D01*
X462624Y352845D01*
Y350339D01*
X465018Y347944D01*
Y343108D01*
X465012Y343102D01*
X463627D01*
G03X463543Y343100I-4J-1601D01*
G01X461111D01*
G03X461027Y343102I-80J-1599D01*
G01X459627D01*
G03X459543Y343100I-4J-1601D01*
G01X457564D01*
G03X454236I-1664J-2000D01*
G01X452165D01*
G03X452100Y343102I-82J-1599D01*
G01X450700D01*
G03X450635Y343100I17J-1601D01*
G01X449900D01*
G37*
G36*
G01X507500Y416500D02*
X504500Y419500D01*
Y452500D01*
X505500Y453500D01*
X533500D01*
X536500Y450500D01*
Y420223D01*
X536798Y419924D01*
Y417002D01*
X536826Y416975D01*
Y416824D01*
X536501Y416500D01*
X507500D01*
G37*
G36*
G01X570300Y396500D02*
X569702Y397098D01*
Y406983D01*
X569709Y407009D01*
G03Y408391I-2509J691D01*
G01X569702Y408417D01*
Y412498D01*
X569700Y412499D01*
Y415013D01*
X569884Y415196D01*
Y416184D01*
X570500Y416800D01*
X581700D01*
X582590Y415910D01*
Y396500D01*
X570300D01*
G37*
G36*
G01X540500D02*
X539207Y397793D01*
Y411768D01*
X540421Y412982D01*
X567518D01*
X568500Y412000D01*
Y397000D01*
X568000Y396500D01*
X540500D01*
G37*
G36*
G01X539618Y414503D02*
X538027Y416094D01*
Y417116D01*
X538035Y417144D01*
G03X538102Y417600I-1535J458D01*
G01Y419200D01*
G03X538011Y419730I-1602J-2D01*
G01X538000Y419762D01*
Y453500D01*
X538900Y454400D01*
X565900D01*
X566800Y453500D01*
Y427247D01*
X568682Y425365D01*
Y415694D01*
X567491Y414503D01*
X539618D01*
G37*
G36*
G01X564391Y377205D02*
X554519Y387077D01*
Y394715D01*
X555037Y395233D01*
X581819D01*
X582590Y394462D01*
Y379420D01*
X580374Y377205D01*
X564391D01*
G37*
G36*
G01X631147Y42182D02*
X630711Y42618D01*
Y52362D01*
X631344Y52995D01*
X633292D01*
X635974Y50313D01*
Y47880D01*
X635967Y47854D01*
G03X635914Y47468I1399J-389D01*
G01Y43146D01*
X635974Y43086D01*
Y42832D01*
X635324Y42182D01*
X631147D01*
G37*
G36*
G01X619400Y161600D02*
X621500Y159500D01*
X627747D01*
X627845Y159402D01*
X642398D01*
X642600Y159200D01*
X646400D01*
X646600Y159000D01*
Y158000D01*
X645700Y157100D01*
X643700D01*
X643000Y157800D01*
X621426D01*
X620885Y157915D01*
X620300Y158500D01*
X618409D01*
X618216Y158625D01*
X615902Y160939D01*
Y163380D01*
X614678Y164604D01*
X614653Y164721D01*
Y168809D01*
X613548Y169914D01*
X613532Y169990D01*
Y182982D01*
X618250Y187700D01*
X630800D01*
X633731Y184769D01*
Y169538D01*
X635069Y168200D01*
X639200D01*
X641200Y166200D01*
X643600D01*
X644000Y165800D01*
Y164900D01*
X643700Y164600D01*
X629700D01*
X629100Y165200D01*
Y167753D01*
X630987Y169640D01*
Y183494D01*
X630381Y184100D01*
X621847D01*
X615704Y177957D01*
Y177131D01*
X615048Y176475D01*
Y171945D01*
X615704Y171289D01*
Y171226D01*
X619400Y167530D01*
Y167365D01*
G03X619398Y167300I1599J-82D01*
G01Y165700D01*
G03X619400Y165635I1601J17D01*
G01Y161600D01*
G37*
G36*
G01X618800Y270450D02*
X617917Y271333D01*
Y279846D01*
X618519Y280448D01*
X622322D01*
X622908Y279862D01*
Y279619D01*
X622907Y279609D01*
G03X622898Y279445I1593J-170D01*
G01Y278045D01*
G03X622907Y277881I1602J6D01*
G01X622908Y277871D01*
Y272513D01*
X622882Y272488D01*
Y271392D01*
X621940Y270450D01*
X618800D01*
G37*
G36*
G01X636971Y310000D02*
X635510Y311461D01*
Y345865D01*
X632878Y348498D01*
Y371554D01*
X636156Y374832D01*
X654972D01*
X656604Y373200D01*
X663901D01*
X664500Y373799D01*
X672031D01*
X672331Y373499D01*
Y372631D01*
X672200Y372500D01*
X667832D01*
X666731Y371399D01*
X655799D01*
X653300Y368900D01*
X653065D01*
G03X653000Y368902I-82J-1599D01*
G01X651400D01*
G03X651335Y368900I17J-1601D01*
G01X642300D01*
X641500Y368100D01*
Y361500D01*
X642500Y360500D01*
X649400D01*
X650331Y359569D01*
Y310931D01*
X649400Y310000D01*
X636971D01*
G37*
G36*
G01X629800Y383800D02*
X629400Y384200D01*
Y384298D01*
G03X629430Y384604I-1572J309D01*
G01Y386004D01*
G03X629403Y386293I-1602J-4D01*
G01X629400Y386311D01*
Y388600D01*
X631800Y391000D01*
X638300D01*
X639300Y390000D01*
Y384600D01*
X638500Y383800D01*
X629800D01*
G37*
G36*
G01X625200Y372000D02*
X624575Y371375D01*
G03X624322Y371124I994J-1255D01*
G01X624315Y371115D01*
X623900Y370700D01*
Y367700D01*
X623800Y367600D01*
X621700D01*
X621650Y367650D01*
X621150D01*
X620900Y367900D01*
Y371700D01*
X622074Y372874D01*
G03X622477Y373273I-907J1320D01*
G01X622487Y373287D01*
X622600Y373400D01*
X624900D01*
X625200Y373100D01*
Y372000D01*
G37*
G36*
G01X629700Y427000D02*
X612500D01*
X612000Y427500D01*
Y435500D01*
X612500Y436000D01*
X629592D01*
X630157Y435435D01*
Y427457D01*
X629700Y427000D01*
G37*
G36*
G01X609000Y473000D02*
X610500Y471500D01*
Y437727D01*
X610486Y437714D01*
Y437218D01*
X609764Y436496D01*
X603122D01*
X602624Y436994D01*
X599290D01*
X598250Y438035D01*
Y469594D01*
X598842Y470185D01*
Y471756D01*
G03X599247Y472240I-1701J1835D01*
G01X599258Y472258D01*
X600000Y473000D01*
X603868D01*
Y472928D01*
X607272D01*
Y473000D01*
X609000D01*
G37*
G36*
G01X615222Y475059D02*
X614781Y475500D01*
X607272D01*
Y475532D01*
X603868D01*
Y475500D01*
X599300D01*
X597050Y477750D01*
X595386D01*
X595385Y477752D01*
X593600D01*
X593300Y478051D01*
Y478335D01*
G03X593302Y478400I-1599J82D01*
G01Y479800D01*
G03X593300Y479865I-1601J-17D01*
G01Y485300D01*
X597000Y489000D01*
X626060D01*
X627021Y488039D01*
Y475848D01*
X626474Y475301D01*
X626452Y475288D01*
G03X626125Y475059I1267J-2157D01*
G01X622567D01*
X622546Y475064D01*
G03X622200Y475102I-347J-1564D01*
G01X620800D01*
G03X620454Y475064I1J-1602D01*
G01X620433Y475059D01*
X618067D01*
X618046Y475064D01*
G03X617700Y475102I-347J-1564D01*
G01X616300D01*
G03X615954Y475064I1J-1602D01*
G01X615933Y475059D01*
X615222D01*
G37*
G36*
G01X599070Y427730D02*
X598016Y428784D01*
Y432817D01*
X598202Y433002D01*
Y435602D01*
X598344Y435744D01*
X601046D01*
X601930Y434860D01*
X608490D01*
X609300Y434050D01*
Y428540D01*
X608490Y427730D01*
X599070D01*
G37*
G36*
G01X577623Y433000D02*
X575965Y434658D01*
Y453928D01*
X579437Y457400D01*
X585630D01*
X586662Y456368D01*
X594757D01*
G03X595718Y456665I1J1701D01*
G01X595769Y456700D01*
X596648D01*
Y443948D01*
X597000D01*
Y435862D01*
X596989Y435830D01*
G03X596898Y435300I1511J-532D01*
G01Y433700D01*
G03X596909Y433516I1602J3D01*
G01X596920Y433420D01*
X596500Y433000D01*
X577623D01*
G37*
G36*
G01X613500Y437500D02*
X612000Y439000D01*
Y443948D01*
X612152D01*
Y455652D01*
X612768Y456268D01*
X616726D01*
X619465Y453528D01*
X619472D01*
X622000Y451000D01*
X636500D01*
X638534Y448966D01*
Y439165D01*
X636869Y437500D01*
X613500D01*
G37*
G36*
G01X649838Y28168D02*
X650622Y28952D01*
X653548D01*
X654259Y28241D01*
X654253Y28150D01*
G03X654342Y27365I2197J-148D01*
G01X654350Y27337D01*
Y26900D01*
X655250Y26000D01*
X655528D01*
X655566Y25983D01*
G03X657371Y26000I884J2017D01*
G01X661300D01*
X661900Y25400D01*
Y19100D01*
X661401Y18601D01*
X650650D01*
X649600Y19651D01*
Y24472D01*
G03X649838Y25268I-1214J797D01*
G01Y28168D01*
G37*
G36*
G01X649912Y43888D02*
X649600Y44200D01*
Y46672D01*
G03X649838Y47468I-1214J797D01*
G01Y50444D01*
X649993Y50600D01*
Y52057D01*
X651472Y53536D01*
X657464D01*
X658500Y52500D01*
Y44500D01*
X657888Y43888D01*
X649912D01*
G37*
G36*
G01X665906Y297995D02*
X654800D01*
X652960Y299835D01*
Y318900D01*
X653260Y319200D01*
X667000D01*
X667531Y318669D01*
Y314383D01*
X667524Y314376D01*
Y299613D01*
X665906Y297995D01*
G37*
G36*
G01X692702Y323402D02*
X693600Y324300D01*
X708300D01*
X709200Y323400D01*
Y303300D01*
X705900Y300000D01*
X693600D01*
X692702Y300898D01*
Y323402D01*
G37*
G36*
G01X652850Y360850D02*
X651700Y362000D01*
X643900D01*
X643500Y362400D01*
Y367100D01*
X644098Y367698D01*
X653798D01*
X653799Y367700D01*
X655587D01*
X657936Y370049D01*
X666931D01*
X667106Y369874D01*
Y367274D01*
X663200Y363368D01*
Y349000D01*
X663800Y348400D01*
X666331D01*
X666631Y348100D01*
Y326290D01*
X666620Y326280D01*
Y321320D01*
X665900Y320600D01*
X653250D01*
X652850Y321000D01*
Y360850D01*
G37*
G36*
G01X736902Y364802D02*
X727048Y354948D01*
Y354748D01*
X726450Y354150D01*
Y326250D01*
X724500Y324300D01*
X710100D01*
X708900Y325500D01*
X708799D01*
X708798Y325502D01*
X693102D01*
X693101Y325500D01*
X691399D01*
X691398Y325502D01*
X680398D01*
X679200Y326700D01*
Y336900D01*
X680400Y338100D01*
X689700D01*
X695300Y343700D01*
Y354900D01*
X695350Y354950D01*
Y360450D01*
X695450Y360550D01*
Y367200D01*
X702350Y374100D01*
X709000D01*
X713500Y378600D01*
Y383000D01*
X714000Y383500D01*
X743000D01*
X744246Y382254D01*
Y369954D01*
X741193Y366900D01*
X739200D01*
X737102Y364802D01*
X736902D01*
G37*
G36*
G01X675900Y300000D02*
X673200Y302700D01*
Y319800D01*
X677550Y324150D01*
X679350D01*
X679500Y324300D01*
X690900D01*
X691500Y323700D01*
Y303165D01*
G03X691498Y303100I1599J-82D01*
G01Y301100D01*
G03X691500Y301035I1601J17D01*
G01Y300900D01*
X690600Y300000D01*
X675900D01*
G37*
G36*
G01X672600Y340200D02*
X671800Y341000D01*
Y356300D01*
X671200Y356900D01*
X665000D01*
X664600Y357300D01*
Y362669D01*
X668531Y366600D01*
Y371383D01*
X669031Y371883D01*
X674964D01*
G03X676361Y371272I1396J1290D01*
G01X678642D01*
X682607Y367307D01*
X688200D01*
X689100Y366407D01*
Y343200D01*
X686100Y340200D01*
X672600D01*
G37*
G36*
G01X692758Y439592D02*
X692350Y440000D01*
Y443600D01*
X691400Y444550D01*
Y450700D01*
X691296Y450804D01*
Y450830D01*
X691270D01*
X690950Y451150D01*
X688600D01*
X688450Y451300D01*
Y463000D01*
X688700Y463250D01*
X691200D01*
X691400Y463450D01*
Y478800D01*
X691898Y479298D01*
X697202D01*
X697698Y478802D01*
Y464902D01*
X697700Y464901D01*
Y463550D01*
X698050Y463200D01*
X700150D01*
X700500Y462850D01*
Y451350D01*
X700300Y451150D01*
X698000D01*
X697750Y450900D01*
Y450630D01*
X697728D01*
Y444226D01*
X697900D01*
Y440096D01*
X697396Y439592D01*
X692758D01*
G37*
G36*
G01X697300Y480500D02*
X686500D01*
X685500Y481500D01*
Y489300D01*
X686300Y490100D01*
X696800D01*
X697600Y489300D01*
Y480800D01*
X697300Y480500D01*
G37*
G36*
G01X672075Y456625D02*
X670300Y458400D01*
Y473500D01*
X671700Y474900D01*
X687400D01*
X689900Y472400D01*
Y465400D01*
X687400D01*
X686900Y464900D01*
Y456900D01*
X686625Y456625D01*
X676728D01*
X676692Y456640D01*
G03X676080Y456762I-613J-1480D01*
G01X674680D01*
G03X674068Y456640I1J-1602D01*
G01X674032Y456625D01*
X672075D01*
G37*
G36*
G01X731100Y85000D02*
X728500Y87600D01*
X724400D01*
X723900Y88100D01*
Y89900D01*
X724250Y90250D01*
X729050D01*
X729600Y89700D01*
X731135D01*
G03X731200Y89698I82J1599D01*
G01X732600D01*
G03X732665Y89700I-17J1601D01*
G01X733800D01*
X734500Y90400D01*
Y91100D01*
X734900Y91500D01*
X736900D01*
X737100Y91300D01*
Y91065D01*
G03X737098Y91000I1599J-82D01*
G01Y89600D01*
G03X737100Y89535I1601J17D01*
G01Y86965D01*
G03X737098Y86900I1599J-82D01*
G01Y85498D01*
X736600Y85000D01*
X731100D01*
G37*
G36*
G01X757700Y82800D02*
X747000D01*
X746000Y83800D01*
Y90800D01*
X746400Y91200D01*
X757800D01*
X758000Y91000D01*
Y83100D01*
X757700Y82800D01*
G37*
G36*
G01X756206Y177952D02*
X755958Y178200D01*
Y198222D01*
X756581Y198845D01*
X762347D01*
X763302Y199800D01*
Y203488D01*
X761669Y205121D01*
X756266D01*
X756023Y205364D01*
Y207014D01*
X756379Y207370D01*
X766698D01*
X768607Y205461D01*
Y179457D01*
X767102Y177952D01*
X756206D01*
G37*
G36*
G01X768420Y296470D02*
X761058Y289108D01*
X749909D01*
X749550Y289467D01*
Y296158D01*
X749552Y296173D01*
G03X749572Y296420I-1582J252D01*
G01Y297820D01*
G03X749570Y297897I-1602J-3D01*
G01X749565Y297985D01*
X749770Y298190D01*
X750190D01*
X750545Y298545D01*
X760455D01*
X761990Y300080D01*
Y301670D01*
X762090Y301770D01*
X768090D01*
X768420Y301440D01*
Y296470D01*
G37*
G36*
G01X748500Y324600D02*
X730200D01*
X728250Y326550D01*
Y354450D01*
X737400Y363600D01*
X748500D01*
X749400Y362700D01*
Y325500D01*
X748500Y324600D01*
G37*
G36*
G01X703300Y397800D02*
X702600Y398500D01*
Y415100D01*
X703392Y415892D01*
X711376D01*
X712298Y414970D01*
Y398798D01*
X711300Y397800D01*
X703300D01*
G37*
G36*
G01X712307Y385464D02*
X705186D01*
X704400Y386250D01*
Y395500D01*
X705200Y396300D01*
X711700D01*
X713500Y398100D01*
Y414989D01*
X713800Y415289D01*
X740273D01*
X741843Y413719D01*
Y389743D01*
X737719Y385619D01*
X712462D01*
X712307Y385464D01*
G37*
G36*
G01X728400Y456400D02*
X717900D01*
X716550Y457750D01*
Y491200D01*
X717250Y491900D01*
X728400D01*
X729225Y491075D01*
Y457225D01*
X728400Y456400D01*
G37*
G36*
G01X741668Y460400D02*
X731400D01*
X730525Y461275D01*
Y477525D01*
X731583Y478583D01*
X741217D01*
X742900Y476900D01*
Y462400D01*
X742890Y462390D01*
Y461622D01*
X741668Y460400D01*
G37*
G36*
G01X711950Y452750D02*
X711200Y453500D01*
Y455300D01*
X710100Y456400D01*
X709771D01*
X709716Y456443D01*
G03X707245Y456614I-1361J-1731D01*
G01X703186D01*
X702400Y457400D01*
Y464400D01*
X702114Y464686D01*
Y464872D01*
X701928D01*
X701900Y464900D01*
X699400D01*
X698972Y465328D01*
Y470316D01*
X698900D01*
Y489400D01*
X701400Y491900D01*
X713900D01*
X715175Y490625D01*
Y455875D01*
X716000Y455050D01*
X718100D01*
X718450Y454700D01*
Y453000D01*
X718200Y452750D01*
X711950D01*
G37*
G36*
G01X798008Y269562D02*
X796753Y270817D01*
Y280442D01*
X795464Y281731D01*
X794516D01*
X794487Y281740D01*
G03X793187I-650J-2104D01*
G01X793158Y281731D01*
X792731D01*
X792283Y282179D01*
Y284223D01*
X792658Y284598D01*
X793656D01*
X793669Y284585D01*
X805610D01*
X806752Y283443D01*
Y269774D01*
X806540Y269562D01*
X806453D01*
G03X806100Y269602I-356J-1562D01*
G01X804500D01*
G03X804166Y269566I4J-1602D01*
G01X804146Y269562D01*
X798008D01*
G37*
G36*
G01X793000Y290000D02*
X792025Y290975D01*
Y293803D01*
X792722Y294500D01*
X803888D01*
X804408Y293980D01*
Y290497D01*
X803911Y290000D01*
X803022D01*
X802999Y290005D01*
G03X802634Y290048I-369J-1559D01*
G01X801234D01*
G03X800869Y290005I4J-1602D01*
G01X800846Y290000D01*
X793000D01*
G37*
G36*
G01X785400Y308110D02*
Y308132D01*
X778158D01*
X778017Y308273D01*
Y310508D01*
X778931Y311422D01*
X787038D01*
X787413Y311047D01*
Y308616D01*
X786907Y308110D01*
X785400D01*
G37*
%LPC*%
G75*
G36*
G01X298800Y184300D02*
X300200Y182900D01*
Y162900D01*
X298300Y161000D01*
X287000D01*
X283000Y165000D01*
Y183000D01*
X284300Y184300D01*
X298800D01*
G37*
G36*
G01X300002Y225348D02*
Y204113D01*
X298595Y202706D01*
X287094D01*
X284298Y205502D01*
Y224498D01*
X286002Y226202D01*
X299148D01*
X300002Y225348D01*
G37*
G54D134*
X76600Y319950D03*
X70600D03*
G54D135*
X462450Y358960D03*
G54D133*
X32100Y164400D03*
Y166600D03*
X52000Y150900D03*
Y153100D03*
X25300Y161500D03*
X27700D03*
X26500Y164400D03*
X30100Y210700D03*
X31800Y274400D03*
X78300Y315100D03*
X76600Y317000D03*
X176800Y191500D03*
X180200D03*
X176800Y200500D03*
X180200D03*
X199894Y208785D03*
Y211185D03*
X94650Y451450D03*
Y453850D03*
X240550Y352650D03*
X246050D03*
X217000Y482800D03*
X273500Y139300D03*
Y142700D03*
X273000Y161300D03*
Y164700D03*
Y181300D03*
Y184700D03*
X273500Y202800D03*
Y206200D03*
Y222800D03*
Y226200D03*
X273000Y244300D03*
Y247700D03*
X227700Y283400D03*
X229600D03*
X228000Y382500D03*
Y385900D03*
X240550Y360250D03*
X246050D03*
X240550Y364750D03*
X246050D03*
X237000Y382500D03*
Y385900D03*
X227400Y409400D03*
X223000Y482800D03*
X282500Y142700D03*
X294800Y146000D03*
X298200D03*
X295300Y157500D03*
X298700D03*
X282000Y161300D03*
Y164700D03*
Y181300D03*
Y184700D03*
X294800Y187800D03*
X298200D03*
X294800Y198600D03*
X298200D03*
X282500Y202800D03*
Y206200D03*
Y222800D03*
Y226200D03*
X295300Y229850D03*
X298700D03*
X294800Y240650D03*
X298200D03*
X282000Y244300D03*
X294800Y137000D03*
Y246250D03*
Y249650D03*
X268700Y283400D03*
X270500D03*
X279269Y374525D03*
X275168Y377100D03*
Y379300D03*
Y381100D03*
Y383300D03*
X277900Y397200D03*
X280100D03*
X347397Y221840D03*
X349797D03*
X336700Y423000D03*
X452500Y345300D03*
X459227Y345301D03*
X461427D03*
X463227D03*
X468896Y355512D03*
X471096D03*
X469297Y357538D03*
Y359738D03*
X534500Y419600D03*
X579300Y400000D03*
X564800D03*
X540500Y417200D03*
Y419600D03*
X564800Y391000D03*
X568200D03*
X579300D03*
X564800Y394400D03*
X568200D03*
X579300D03*
X617000Y165300D03*
Y167700D03*
X631000D03*
X620700Y277645D03*
X651000Y371300D03*
X653400D03*
X631628Y386404D03*
X617570Y432230D03*
X614170D03*
X622300Y432200D03*
X618900D03*
X624823Y476731D03*
X615900Y477300D03*
X618100D03*
X620400D03*
X622600D03*
X624823Y478931D03*
X595500Y480200D03*
X600500Y433300D03*
X594500Y435700D03*
X632250Y439050D03*
X618900Y441200D03*
X622300D03*
X614170Y441230D03*
X617570D03*
X632250Y443550D03*
X695100Y303500D03*
X696600Y304600D03*
Y308000D03*
X664283Y345818D03*
X651000Y365300D03*
X653400D03*
X680200Y329100D03*
X683600D03*
X717500Y380100D03*
X689100Y303500D03*
X687600Y304600D03*
Y308000D03*
X680200Y320100D03*
X683600D03*
X684600Y363800D03*
X688000D03*
X694735Y442396D03*
X674280Y458960D03*
X676480D03*
X734900Y87300D03*
X730800Y87500D03*
X733000D03*
X734900Y89200D03*
X748000Y89300D03*
X756623Y89015D03*
X754423D03*
X752123D03*
X749923D03*
X748000Y87400D03*
Y85200D03*
X758118Y180153D03*
Y182053D03*
Y184253D03*
Y186153D03*
Y188353D03*
X758130Y196100D03*
X751770Y296020D03*
X756288Y296361D03*
X758688D03*
X717500Y389100D03*
X714100D03*
X718900Y490600D03*
Y488200D03*
X727100Y476500D03*
Y474300D03*
X726900Y465100D03*
Y462700D03*
X732700Y476500D03*
Y474300D03*
X732900Y465100D03*
X738100Y463900D03*
X734700D03*
X732900Y462700D03*
X714350Y454995D03*
X712900Y488200D03*
Y490600D03*
X804100Y272000D03*
X800834Y292246D03*
X803034D03*
X795955Y292267D03*
X798355D03*
%LPD*%
G75*
G36*
G01X298100Y162500D02*
X287500D01*
X284500Y165500D01*
Y182500D01*
X285000Y183000D01*
X297671D01*
X298800Y181871D01*
Y163200D01*
X298100Y162500D01*
G37*
G36*
G01X298097Y203908D02*
X287592D01*
X285500Y206000D01*
Y224000D01*
X286500Y225000D01*
X298650D01*
X298800Y224850D01*
Y204611D01*
X298097Y203908D01*
G37*
%LPC*%
G75*
G54D133*
X294800Y178800D03*
X295300Y166500D03*
Y220850D03*
X294800Y207600D03*
%LPD*%
G75*
G54D100*
X632800Y341500D03*
X629200D03*
X632800Y302891D03*
X629200D03*
X693900Y302100D03*
X690300D03*
G54D101*
X629400Y405234D03*
X609400D03*
X619400Y417046D03*
X599400D03*
X761520Y350206D03*
X781520D03*
X771520Y338394D03*
X791520D03*
G54D110*
X665245Y373173D03*
G54D120*
G01X45150Y204779D02*
X40914D01*
X39301Y203166D01*
G01X45150Y206747D02*
X39547D01*
X39416Y206616D01*
G01X34380Y203183D02*
X35984D01*
X39416Y206615D01*
Y206616D01*
G01X29900Y203550D02*
X32126D01*
X32493Y203183D01*
X34380D01*
G01X64650Y204779D02*
X69721D01*
X72100Y202400D01*
X72300D01*
G01X59800Y193700D02*
Y194900D01*
X57853Y196847D01*
Y199950D01*
G01X195161Y131567D02*
X190033D01*
X189116Y132484D01*
X183906D01*
G01Y134453D02*
X180753D01*
X179800Y133500D01*
G01D02*
X177800Y131500D01*
G01X171694Y134453D02*
X169271D01*
X167502Y136222D01*
Y137140D01*
X165097Y139545D01*
G01X174847Y137606D02*
Y139806D01*
X173800Y140853D01*
X172948D01*
X172800Y141001D01*
G01X594050Y301755D02*
X596516Y299289D01*
X605020D01*
G01X629250Y299091D02*
X626198D01*
X626000Y299289D01*
X621320D01*
G01X605020Y337698D02*
X609902D01*
X610750Y336850D01*
G01X629250Y337500D02*
X626198D01*
X626000Y337698D01*
X621320D01*
G01X598152Y366291D02*
X600802D01*
X601338Y365755D01*
X605020D01*
G01X598023Y389961D02*
X598907D01*
X600733Y388135D01*
X605020D01*
G01X598023Y386461D02*
X599857D01*
X600153Y386165D01*
X605020D01*
G01X598152Y362791D02*
X600634D01*
X601628Y363785D01*
X605020D01*
G01X623520Y389940D02*
X620260D01*
G01D02*
X619940D01*
X618135Y388135D01*
X614220D01*
G01X622820Y369320D02*
X621668D01*
G01D02*
X618103Y365755D01*
X614220D01*
G01X594757Y460037D02*
X588663D01*
G01X646456Y111811D02*
X649606D01*
G01X655905Y114960D02*
X654330Y113385D01*
G01X649606Y111811D02*
X649607D01*
X652756Y114960D01*
G01X646456Y111811D02*
Y114960D01*
G01X687401D02*
X688976Y113385D01*
G01X654330D02*
X652756Y114959D01*
Y114960D01*
G01X644100Y111811D02*
X646456D01*
G01X678189Y108784D02*
Y109211D01*
X677952Y109448D01*
Y111811D01*
G01X699563Y108815D02*
X696850Y111528D01*
Y111811D01*
G01X657480Y113385D02*
X659054Y111811D01*
X659055D01*
G01X669500Y108400D02*
X668504Y109396D01*
Y111811D01*
G01X689049Y109487D02*
X687401Y111135D01*
Y111811D01*
G01X640600Y111600D02*
Y113165D01*
X642395Y114960D01*
X643307D01*
G01X655905Y155905D02*
X654330Y154330D01*
G01X684252Y118110D02*
Y118111D01*
X687401Y121260D01*
G01X659055Y124409D02*
X657480Y122834D01*
G01X655905Y124409D02*
X657480Y122834D01*
G01D02*
X659054Y121260D01*
X659055D01*
G01X646456Y114960D02*
X649606Y118110D01*
G01X643307Y165354D02*
X641554D01*
X639108Y167800D01*
G01X646456Y133858D02*
X648032Y135434D01*
G01X649606Y137008D02*
X648032Y135434D01*
G01X649606Y124409D02*
X648032Y122835D01*
G01X659055Y118110D02*
X660629Y116536D01*
G01X676377D02*
X674803Y118110D01*
G01X668504Y114960D02*
X666929Y116535D01*
G01X665354Y118110D02*
X666929Y116535D01*
G01X674803Y127559D02*
X673229Y125985D01*
G01X681102Y127559D02*
X679528Y125985D01*
G01X693700Y127559D02*
Y127567D01*
X692148Y129119D01*
G01X696850Y124409D02*
X696852D01*
X698426Y122835D01*
G01X696850Y114960D02*
X698425Y116535D01*
G01X646456Y159055D02*
Y159054D01*
X644882Y157480D01*
G01X643307Y159055D02*
X644882Y157480D01*
G01X652756Y159055D02*
X651181Y157480D01*
G01X649606Y159055D02*
X651181Y157480D01*
G01X646456Y165354D02*
X648031Y163779D01*
G01X690551Y118110D02*
X687401Y114960D01*
G01X693700Y118110D02*
X696850D01*
G01X674803D02*
X674482D01*
X674057Y117685D01*
X674019D01*
X673985Y117651D01*
X672407D01*
X671948Y118110D01*
X671653D01*
G01D02*
X671332D01*
X670907Y117685D01*
X670870D01*
X670858Y117673D01*
X669226D01*
X668789Y118110D01*
X668504D01*
G01X666929Y116535D02*
X668504Y118110D01*
G01X659055Y114960D02*
Y114962D01*
X660629Y116536D01*
G01D02*
X662203Y118110D01*
X662204D01*
G01X649606Y121260D02*
Y121261D01*
X648032Y122835D01*
G01D02*
X646458Y124409D01*
X646456D01*
G01X648032Y135434D02*
X649606Y133860D01*
Y133858D01*
G01Y140157D02*
Y140172D01*
X648057Y141721D01*
G01D02*
X646471Y143307D01*
X646456D01*
G01X648057Y141721D02*
X648063Y141727D01*
Y141764D01*
X649606Y143307D01*
G01X677952Y114960D02*
Y114961D01*
X676377Y116536D01*
G01D02*
X677951Y118110D01*
X677952D01*
G01X651181Y157480D02*
X649606Y155905D01*
G01X654330Y163779D02*
X652756Y165353D01*
Y165354D01*
G01X698425Y116535D02*
X696850Y118110D01*
G01X648031Y163779D02*
X649606Y162204D01*
G01X659055Y118110D02*
X658285Y118880D01*
Y120490D01*
X659055Y121260D01*
G01X662204Y171653D02*
X663778Y173227D01*
G01X668504Y127559D02*
X666929Y125984D01*
G01X668504Y127559D02*
X671653Y130708D01*
G01X681102Y118110D02*
X677952Y114960D01*
G01X687401Y124409D02*
Y124411D01*
X685827Y125985D01*
G01X652756Y152756D02*
X651181Y151181D01*
G01X668504Y124409D02*
X666929Y125984D01*
G01X677952Y124409D02*
X679528Y125985D01*
G01X649606Y130708D02*
X648032Y129134D01*
G01X649606Y127559D02*
Y127560D01*
X648032Y129134D01*
G01X687401Y121260D02*
X686624Y122037D01*
Y123632D01*
X687401Y124409D01*
G01X665354Y130708D02*
X668504Y133858D01*
G01X662204Y140157D02*
X660629Y141732D01*
G01X659055Y140157D02*
X655905Y143307D01*
G01D02*
X655906D01*
X659055Y146456D01*
G01X655905Y133858D02*
X659055Y137008D01*
G01X660629Y138584D02*
X659055Y137010D01*
Y137008D01*
G01X679527Y173229D02*
X681101Y174803D01*
X681102D01*
G01X690551Y171653D02*
X692126Y173228D01*
G01X696850Y171653D02*
X698425Y173228D01*
G01X690551Y165354D02*
X692126Y166929D01*
G01X687401Y168504D02*
X685826Y166929D01*
G01X681102Y168504D02*
X679527Y166929D01*
G01X687401Y162204D02*
X685826Y160629D01*
G01X684252Y152756D02*
X685826Y154330D01*
G01X681102Y149606D02*
X679527Y148031D01*
G01X687401Y149606D02*
X685826Y148031D01*
G01X690551Y146456D02*
X692126Y148031D01*
G01X685826Y173228D02*
X684252Y171654D01*
Y171653D01*
G01X690551Y159055D02*
X690552D01*
X692126Y160629D01*
G01X690551Y152756D02*
X690552D01*
X692126Y154330D01*
G01Y141732D02*
X693700Y143306D01*
Y143307D01*
G01X679527Y166929D02*
X677952Y165354D01*
G01X685826Y166929D02*
X684252Y165355D01*
Y165354D01*
G01X692126Y166929D02*
X693700Y168503D01*
Y168504D01*
G01X698425Y166929D02*
X696850Y165354D01*
G01X685826Y160629D02*
X684252Y159055D01*
G01X692126Y160629D02*
X693700Y162203D01*
Y162204D01*
G01X698425Y160629D02*
X696851Y159055D01*
X696850D01*
G01X698425Y154330D02*
X696851Y152756D01*
X696850D01*
G01X692126Y154330D02*
X693700Y155904D01*
Y155905D01*
G01X685826Y154330D02*
X687401Y155905D01*
G01X698425Y148031D02*
X696850Y146456D01*
G01X692126Y148031D02*
X693700Y149605D01*
Y149606D01*
G01X685826Y148031D02*
X684252Y146457D01*
Y146456D01*
G01X668504Y168504D02*
X670078Y170078D01*
G01X655905Y171653D02*
X654330Y173228D01*
G01D02*
X652756Y174802D01*
Y174803D01*
G01Y168504D02*
X651181Y166929D01*
G01X652756Y162204D02*
X649606Y165354D01*
G01X651181Y166929D02*
X649606Y165354D01*
G01X666929Y129134D02*
X668503Y130708D01*
X668504D01*
G01X663778Y138584D02*
X662204Y137010D01*
Y137008D01*
G01X663778Y144883D02*
X662204Y143309D01*
Y143307D01*
G01X668504Y149606D02*
X666929Y148031D01*
G01X662204Y149606D02*
X663779Y151181D01*
G01X662204Y130708D02*
X663779Y132283D01*
G01X652756Y143307D02*
X651181Y141732D01*
G01X652756Y124409D02*
X651181Y122834D01*
G01X652756Y133858D02*
X651181Y132283D01*
G01X640500Y125000D02*
X642716D01*
X643307Y124409D01*
G01X644882Y154331D02*
X643307Y152756D01*
G01X660629Y144883D02*
X659055Y143309D01*
Y143307D01*
G01X671653Y152756D02*
X670078Y151181D01*
G01Y157480D02*
X668504Y155906D01*
Y155905D01*
G01X674803Y149606D02*
X673228Y148031D01*
G01X671653Y127559D02*
X670079Y125985D01*
G01X684252Y127559D02*
X682678Y125985D01*
G01X677952Y127559D02*
X676378Y125985D01*
G01X690551Y127559D02*
X688977Y125985D01*
G01X677952Y121260D02*
X676378Y119686D01*
G01X685827Y116535D02*
X687401Y118109D01*
Y118110D01*
G01X665354Y127559D02*
X663780Y125985D01*
G01X690551Y177952D02*
X692126Y179527D01*
G01X693700Y193700D02*
X693701D01*
X696850Y190551D01*
G01X640931Y181102D02*
X643307D01*
G01X706299Y124409D02*
X704725Y122835D01*
G01X700000Y124409D02*
X698426Y122835D01*
G01X703149Y121260D02*
X703150D01*
X704725Y122835D01*
G01X718897Y124409D02*
X717322Y122834D01*
G01X715748Y121260D02*
X717322Y122834D01*
G01X711023D02*
X712598Y124409D01*
G01X725196D02*
Y124408D01*
X723622Y122834D01*
G01X709448Y121260D02*
X709449D01*
X711023Y122834D01*
G01X722047Y121260D02*
X722048D01*
X723622Y122834D01*
G01X725196Y162204D02*
Y162205D01*
X722047Y165354D01*
G01X703149Y171653D02*
X704724Y173228D01*
G01X706299Y168504D02*
X704724Y166929D01*
G01X700000Y168504D02*
X698425Y166929D01*
G01X706299Y162204D02*
X704724Y160629D01*
G01X700000Y162204D02*
X698425Y160629D01*
G01X700000Y155905D02*
X698425Y154330D01*
G01X706299Y155905D02*
X704724Y154330D01*
G01X700000Y149606D02*
X698425Y148031D01*
G01X706299Y149606D02*
X704724Y148031D01*
G01X700000Y143307D02*
X698425Y141732D01*
G01X706299Y143307D02*
X706298D01*
X703149Y146456D01*
G01X704724Y173228D02*
X706299Y174803D01*
G01X704724Y166929D02*
X703149Y165354D01*
G01X704724Y160629D02*
X703150Y159055D01*
X703149D01*
G01X704724Y154330D02*
X703150Y152756D01*
X703149D01*
G01X704724Y148031D02*
X703149Y146456D01*
G01X706299Y121260D02*
X707874Y122835D01*
G01X715748Y124409D02*
X714173Y122834D01*
G01X722047Y124409D02*
X720472Y122834D01*
G01X707874Y122835D02*
X709448Y124409D01*
G01X720472Y122834D02*
X718898Y121260D01*
X718897D01*
G01X714173Y122834D02*
X712599Y121260D01*
X712598D01*
G01X700000D02*
X701575Y122835D01*
G01D02*
X703149Y124409D01*
G01X700000Y177952D02*
X701575Y179527D01*
G01X715748Y190551D02*
X712598Y187401D01*
G01X715748D02*
X715747D01*
X712598Y184252D01*
G01X762337Y280164D02*
X753858D01*
G01X771537D02*
X775149D01*
X776653Y278660D01*
X778440D01*
G01X771537Y282134D02*
X778414D01*
X778440Y282160D01*
G54D111*
X676361Y379078D03*
Y377110D03*
Y375141D03*
Y373173D03*
X659545Y379078D03*
Y375141D03*
Y377110D03*
G54D102*
X604400Y456100D03*
G54D130*
G01X671653Y124409D02*
X670079Y122835D01*
G01X674803Y124409D02*
X673229Y122835D01*
G01X681102Y124409D02*
X679528Y122835D01*
G01X684252Y124409D02*
X682678Y122835D01*
G01X690551Y124409D02*
X688977Y122835D01*
G01X690551Y121260D02*
X688976Y119685D01*
G01X693700Y124409D02*
X692126Y122835D01*
G01X693700Y121260D02*
X692126Y119686D01*
G54D121*
G01X228669Y81399D02*
Y77831D01*
X231250Y75250D01*
Y73000D01*
G01X243049Y87899D02*
Y91451D01*
X241750Y92750D01*
Y95000D01*
G01X223549Y87899D02*
Y91451D01*
X222250Y92750D01*
Y95000D01*
G01X248100Y475800D02*
X253100D01*
X262672Y466228D01*
Y460813D01*
G01X283100Y424400D02*
Y428107D01*
X262672Y448535D01*
Y460813D01*
G01X299635Y292650D02*
Y298836D01*
X297498Y300973D01*
Y304389D01*
G01X327365Y429161D02*
Y433732D01*
G01X539000Y453000D02*
Y468000D01*
X551550Y480550D01*
G01X570300Y489700D02*
X560700D01*
X551550Y480550D01*
G54D103*
X614043Y465943D03*
Y463974D03*
Y462006D03*
Y460037D03*
Y458069D03*
Y456100D03*
Y454131D03*
Y452163D03*
Y450194D03*
Y448226D03*
Y446257D03*
X594757D03*
Y448226D03*
Y450194D03*
Y452163D03*
Y454131D03*
Y456100D03*
Y458069D03*
Y460037D03*
Y462006D03*
Y463974D03*
Y465943D03*
G54D112*
X674843Y382565D03*
X672874D03*
X663032D03*
X661063D03*
X665000D03*
X666969D03*
X668937D03*
X670906D03*
G54D10*
G01X52957Y175552D02*
X50803Y177706D01*
X44644D01*
X41617Y180733D01*
Y183405D01*
G01X52957Y175552D02*
Y172152D01*
X52607Y171802D01*
G01X56457Y175552D02*
Y171952D01*
X56607Y171802D01*
G01X54370Y180718D02*
Y178551D01*
X56457Y176464D01*
Y175552D01*
G01X59997Y140952D02*
X62300Y143255D01*
Y157667D01*
X58962Y161005D01*
G01X52607Y168302D02*
Y167359D01*
X54697Y165269D01*
G01X58962Y161005D02*
X54698Y165269D01*
X54697D01*
G01X66403Y140952D02*
X64862Y142493D01*
Y152205D01*
G01X56607Y168302D02*
Y167359D01*
X58697Y165269D01*
G01D02*
X64862Y159104D01*
Y152205D01*
G01X75500Y231050D02*
Y227100D01*
X74700Y226300D01*
G01X64650Y214621D02*
X67021D01*
X67800Y215400D01*
Y220894D01*
X73206Y226300D01*
X74700D01*
G01X70500Y231050D02*
Y227700D01*
X69000Y226200D01*
G01X64950Y216590D02*
Y222150D01*
X69000Y226200D01*
G01X76425Y191400D02*
X70825Y197000D01*
X67700D01*
X65050Y199650D01*
X61790D01*
G01X81300Y188000D02*
X79825D01*
X76425Y191400D01*
G01X41617Y183405D02*
Y189254D01*
X49979Y197616D01*
Y199950D01*
G01X55884D02*
Y192658D01*
X54370Y191144D01*
Y180718D01*
G01X46194Y179835D02*
X46500Y180141D01*
Y183450D01*
G01X50194Y179835D02*
X50500Y180141D01*
Y183450D01*
G01X68400Y193400D02*
X66000D01*
X62900Y196500D01*
X61100D01*
X59821Y197779D01*
Y199950D01*
G01X72800Y186650D02*
X69650D01*
X68400Y187900D01*
G01X76800Y186650D02*
X72800D01*
G01X68400Y187900D02*
Y193400D01*
G01X39320Y213823D02*
X36773D01*
X34850Y211900D01*
G01D02*
X36066Y210684D01*
X45150D01*
G01X52400Y231050D02*
X56527D01*
X56541Y231036D01*
G01X61817Y242333D02*
Y233618D01*
X59235Y231036D01*
X56541D01*
G01X55884Y219450D02*
Y226016D01*
X55800Y226100D01*
G01X52400Y231050D02*
Y230100D01*
X55800Y226700D01*
Y226100D01*
G01X64650Y206747D02*
X71947D01*
X75900Y210700D01*
X77600D01*
G01X64650Y208716D02*
X70616D01*
X79050Y217150D01*
G01X29900Y207050D02*
X25900D01*
G01X45150Y208716D02*
X38187D01*
X36871Y207400D01*
X35200D01*
G01D02*
X32194D01*
X31844Y207050D01*
X29900D01*
G01X76100Y197000D02*
X73800Y199300D01*
X71010D01*
X67500Y202810D01*
X64950D01*
G01X82800Y199400D02*
X79800D01*
X77400Y197000D01*
X76100D01*
G01X33700Y223450D02*
X37850D01*
X38850Y222450D01*
G01D02*
X40517Y220783D01*
Y219583D01*
X43510Y216590D01*
X44850D01*
G01X61790Y219750D02*
Y224813D01*
X63206Y226229D01*
G01X65500Y231050D02*
Y228523D01*
X63206Y226229D01*
G01X36199Y191548D02*
Y192013D01*
X36286Y192100D01*
X40400D01*
G01X36199Y191548D02*
Y189437D01*
X36405Y189231D01*
Y187767D01*
G01X40400Y192100D02*
X41300D01*
X48010Y198810D01*
Y199650D01*
G01X71850Y221000D02*
Y216100D01*
G01X64650Y210684D02*
X66884D01*
X71850Y215650D01*
Y216100D01*
G01X46750Y190700D02*
Y191275D01*
X51947Y196472D01*
Y199950D01*
G01X46750Y190700D02*
Y187200D01*
X46500Y186950D01*
G01X50250Y190700D02*
Y187200D01*
X50500Y186950D01*
G01X50250Y190700D02*
Y191663D01*
X53916Y195329D01*
Y199950D01*
G01X61817Y242333D02*
Y244217D01*
X63626Y246026D01*
Y250139D01*
G01X65500Y375550D02*
Y378800D01*
G01X43000Y374983D02*
Y378233D01*
G01X22000Y375102D02*
Y378352D01*
G01X89800Y186850D02*
X85700D01*
G01D02*
X82450D01*
X81300Y188000D01*
G01X84050Y213800D02*
Y210650D01*
X82800Y209400D01*
G01X84050Y217900D02*
Y213800D01*
G01X82800Y209400D02*
X78900D01*
X77600Y210700D01*
G01X91300Y223650D02*
X87300D01*
G01X82600Y222500D02*
Y220700D01*
X79050Y217150D01*
G01X87300Y223650D02*
X83750D01*
X82600Y222500D01*
G01X85550Y194900D02*
Y196650D01*
X82800Y199400D01*
G01X85550Y190900D02*
Y194900D01*
G01X85795Y375176D02*
Y378426D01*
G01X182100Y105500D02*
X181100Y104500D01*
X176300D01*
G01D02*
Y106750D01*
X179550Y110000D01*
G01D02*
X183550D01*
G01D02*
Y111350D01*
X181050Y113850D01*
Y114500D01*
G01X160520Y104310D02*
X157890D01*
X155991Y106209D01*
Y110061D01*
G01X160520Y104310D02*
Y108580D01*
X160050Y109050D01*
G01X177550Y114500D02*
Y111500D01*
X176050Y110000D01*
G01X200550Y111350D02*
X201139Y111939D01*
Y114645D01*
G01X170050Y109625D02*
Y114500D01*
G01X170300Y104500D02*
X170050Y104750D01*
Y109625D01*
G01X183906Y128547D02*
Y126736D01*
X185055Y125587D01*
X189376D01*
X190424Y124539D01*
Y122651D01*
G01X189413Y118094D02*
X190424Y119105D01*
Y122651D01*
G01X175300Y144500D02*
Y142900D01*
X176816Y141384D01*
Y137606D01*
G01X178800Y144500D02*
X178784Y144484D01*
Y137606D01*
G01X156700Y136250D02*
X159250D01*
X161299Y134201D01*
X165319D01*
G01X171694Y132484D02*
X167889D01*
X166172Y134201D01*
X165319D01*
G01X156700Y136250D02*
X154516D01*
X154266Y136500D01*
X152700D01*
G01X178784Y125394D02*
Y120016D01*
X181050Y117750D01*
Y114500D01*
G01X171694Y130516D02*
X169816D01*
X167000Y127700D01*
X164800D01*
X163900Y128600D01*
X162500D01*
G01X160050Y122000D02*
Y117700D01*
G01Y122000D02*
Y123350D01*
X162500Y125800D01*
Y128600D01*
G01X177550Y114500D02*
X173550D01*
G01D02*
Y116452D01*
X176083Y118985D01*
G01D02*
X176816Y119718D01*
Y125394D01*
G01X195161Y128067D02*
X190461D01*
G01X183906Y130516D02*
X186040D01*
X188489Y128067D01*
X190461D01*
G01X183498Y151582D02*
Y145380D01*
G01X180753Y137606D02*
Y139953D01*
X183498Y142698D01*
Y145380D01*
G01X188657Y153196D02*
X185112D01*
X183498Y151582D01*
G01X201139Y114645D02*
X201138Y114644D01*
X196863D01*
G01X174847Y125394D02*
Y121447D01*
X170050Y116650D01*
Y114500D01*
G01X180753Y125394D02*
Y121555D01*
X183760Y118548D01*
G01X193363Y114644D02*
X193313Y114594D01*
X189413D01*
G01D02*
X187714D01*
X183760Y118548D01*
G01X193363Y114644D02*
X193463Y114744D01*
Y118544D01*
G01X151697Y131670D02*
X155620D01*
X156700Y132750D01*
G01X145585Y132451D02*
X146366Y131670D01*
X151697D01*
G01X258700Y304350D02*
X272550D01*
X275000Y301900D01*
Y295983D01*
X280783Y290200D01*
Y288099D01*
X284276Y284606D01*
Y283453D01*
X286991Y280738D01*
Y278576D01*
G01X258700Y304350D02*
X255850D01*
X253350Y306850D01*
X240200D01*
G01X222000Y306750D02*
Y310600D01*
G01Y306750D02*
X240100D01*
X240200Y306850D01*
G01X255500Y419250D02*
Y423361D01*
G01X269500Y409600D02*
X268900Y409000D01*
X261065D01*
X259744Y407679D01*
Y405313D01*
G01X256172Y409530D02*
X255807Y409165D01*
Y405313D01*
G01X261713D02*
X264502D01*
X266825Y402990D01*
X269954D01*
G01X236820Y417395D02*
Y426220D01*
X238370Y427770D01*
X252954D01*
X254224Y426500D01*
X256000D01*
G01X265250Y374200D02*
Y376575D01*
X262325Y379500D01*
X261803D01*
X257776Y383527D01*
Y386027D01*
G01X257941Y371827D02*
Y369718D01*
X261996Y365663D01*
G01X270618Y382200D02*
X267134D01*
X263307Y386027D01*
X261713D01*
G01X255500Y415750D02*
Y414500D01*
X253839Y412839D01*
Y405313D01*
G01X259744Y386027D02*
Y383756D01*
X261500Y382000D01*
X263462D01*
X266111Y379351D01*
G01X253839Y386027D02*
Y379381D01*
X254720Y378500D01*
Y376270D01*
G01D02*
X254441Y375991D01*
Y371827D01*
G01D02*
Y369218D01*
X257996Y365663D01*
G01X256900Y380900D02*
Y381709D01*
X255807Y382802D01*
Y386027D01*
G01X259500Y426500D02*
X262000Y429000D01*
Y431000D01*
G01D02*
X271250D01*
X275500Y426750D01*
Y413800D01*
G01X236820Y439281D02*
Y432259D01*
X239109Y429970D01*
X252722D01*
X253752Y431000D01*
X256000D01*
G01X286991Y278576D02*
X303285D01*
X305800Y281091D01*
Y306370D01*
X313930Y314500D01*
X333200D01*
X338417Y319717D01*
X341641D01*
G01X269500Y416750D02*
Y409600D01*
G01X275500Y409250D02*
Y413800D01*
G01X279000Y405750D02*
X275500D01*
G01X283000D02*
X279000D01*
G01Y401750D02*
X281000D01*
X283000Y403750D01*
Y405750D01*
G01X269954Y402990D02*
X272714Y405750D01*
X275500D01*
G01X283000Y409250D02*
X279000D01*
G01X283050Y413600D02*
Y409300D01*
X283000Y409250D01*
G01X283050Y413600D02*
Y415950D01*
X283100Y416000D01*
Y418400D01*
G01X269977Y373425D02*
X274719D01*
G01X269977D02*
X266025D01*
X265250Y374200D01*
G01X270618Y385867D02*
Y382200D01*
G01Y378200D02*
X267262D01*
X266111Y379351D01*
G01X263250Y420300D02*
Y423411D01*
G01X341650Y323900D02*
Y319726D01*
X341641Y319717D01*
G01X423228Y273623D02*
X419291Y277560D01*
G01X427165Y269686D02*
X423228Y273623D01*
G01X427165Y277560D02*
X423228Y273623D01*
G01X431102D02*
X427165Y277560D01*
G01X403543Y257874D02*
Y259265D01*
X401743Y261065D01*
Y263949D01*
X403543Y265749D01*
G01X395669Y257874D02*
X397469Y256074D01*
X401743D01*
X403543Y257874D01*
G01X423228Y281497D02*
X427165Y277560D01*
G01X419291Y269686D02*
X423228Y265749D01*
G01X403543Y281497D02*
X401743Y283297D01*
X397469D01*
X395669Y281497D01*
G01Y273623D02*
X393869Y275423D01*
Y279697D01*
X395669Y281497D01*
G01X403543Y273623D02*
X401743Y275423D01*
X397469D01*
X395669Y273623D01*
G01Y265749D02*
X393869Y267549D01*
Y271823D01*
X395669Y273623D01*
G01Y257874D02*
X393869Y259674D01*
Y263949D01*
X395669Y265749D01*
G01X403543D02*
X405343Y263949D01*
X413554D01*
X415354Y265749D01*
G01X423228D02*
X421327Y263848D01*
X417255D01*
X415354Y265749D01*
G01X423228D02*
X425029Y267550D01*
X429301D01*
X431102Y265749D01*
G01Y273623D02*
X433003Y271722D01*
Y267650D01*
X431102Y265749D01*
G01X415354Y281497D02*
X417255Y283398D01*
X421327D01*
X423228Y281497D01*
G01X411417Y297245D02*
X409617Y299045D01*
X405343D01*
X403543Y297245D01*
G01D02*
X401743Y299045D01*
X397469D01*
X395669Y297245D01*
G01Y289371D02*
X397469Y291171D01*
X401743D01*
X403543Y289371D01*
G01X395669D02*
X393869Y291171D01*
Y295445D01*
X395669Y297245D01*
G01D02*
X393869Y299045D01*
Y303319D01*
X395669Y305119D01*
G01X403543Y289371D02*
X405343Y291171D01*
X409617D01*
X411417Y289371D01*
G01X395669D02*
X393869Y287571D01*
Y283297D01*
X395669Y281497D01*
G01X415354D02*
X411417D01*
G01X403543D02*
X405343Y283297D01*
X409617D01*
X411417Y281497D01*
G01X395669Y312993D02*
X397469Y314793D01*
X401743D01*
X403543Y312993D01*
G01X395669Y305119D02*
X397469Y306919D01*
X401743D01*
X403543Y305119D01*
G01D02*
X405343Y306919D01*
X409617D01*
X411417Y305119D01*
G01X395669Y312993D02*
X393869Y311193D01*
Y306919D01*
X395669Y305119D01*
G01Y320867D02*
X393769Y318967D01*
Y314893D01*
X395669Y312993D01*
G01Y320867D02*
X397569Y322767D01*
X401643D01*
X403543Y320867D01*
G01X490158Y297245D02*
Y301182D01*
G01X517500Y297218D02*
X517473Y297245D01*
X513780D01*
G01X518647Y288943D02*
X518219Y289371D01*
X513780D01*
G01X586600Y482900D02*
X564046D01*
X561746Y480600D01*
G01X573570Y463730D02*
X571070Y466230D01*
X569070D01*
G01X561746Y480600D02*
X558530Y477384D01*
Y467570D01*
X559870Y466230D01*
X569070D01*
G01X562460Y471070D02*
X570080D01*
X574250Y466900D01*
G01X582399Y441531D02*
X573369D01*
X572300Y442600D01*
Y456568D01*
X573570Y457838D01*
Y460230D01*
G01X560513Y441531D02*
X569031D01*
X570100Y442600D01*
Y456515D01*
X569070Y457545D01*
Y460230D01*
G01X590640Y472600D02*
X590310Y472930D01*
X586720D01*
G01X590640Y472600D02*
X591610Y471630D01*
Y467860D01*
X591165Y467415D01*
Y465335D01*
X592526Y463974D01*
X594757D01*
G01X629820Y468430D02*
X633280D01*
X634050Y469200D01*
G01X588400Y469450D02*
X587480Y468530D01*
X584520D01*
G01D02*
Y464580D01*
X587094Y462006D01*
X594757D01*
G01Y465943D02*
Y468507D01*
X597140Y470890D01*
Y473590D01*
G01X590050Y486650D02*
Y482950D01*
X590100Y482900D01*
G01D02*
Y479950D01*
X590950Y479100D01*
G01X597140Y473590D02*
X594680Y476050D01*
X592895D01*
X590950Y477995D01*
Y479100D01*
G01X586720Y476430D02*
X583220D01*
X582855Y476795D01*
G01D02*
X581250Y478400D01*
Y480550D01*
G01X585420Y456480D02*
X585800Y456100D01*
X594757D01*
G01X629373Y477831D02*
Y474785D01*
X627718Y473130D01*
G01D02*
X626320Y471732D01*
Y468430D01*
G01D02*
X620127Y462237D01*
X618088D01*
X617857Y462006D01*
X614043D01*
G01X617000Y468700D02*
Y467000D01*
X615943Y465943D01*
X614043D01*
G01X617000Y472750D02*
Y468700D01*
G01X633676Y460080D02*
X629370D01*
G01X584450Y460300D02*
X585136D01*
X587367Y458069D01*
X594757D01*
G01X621500Y468000D02*
Y472750D01*
G01X614043Y463974D02*
X617474D01*
X621500Y468000D01*
G01X624770Y455230D02*
X620170D01*
X617331Y458069D01*
X614043D01*
G01X624770Y455230D02*
X628020D01*
X629370Y456580D01*
G01X620600Y458500D02*
X619063Y460037D01*
X614043D01*
G01X590050Y490400D02*
Y486650D01*
G01X576300Y489700D02*
X581500D01*
G01X586550Y490400D02*
X584200D01*
X583500Y489700D01*
X581500D01*
G01X586550Y486650D02*
Y490400D01*
G01X664000Y53750D02*
X665750D01*
X668100Y56100D01*
G01X665012Y65659D02*
Y61600D01*
X664000Y60588D01*
Y57250D01*
G01X660375Y70750D02*
X661860D01*
X665012Y67598D01*
Y65659D01*
G01X671653Y171653D02*
X671652D01*
X670078Y173227D01*
G01X635852Y133715D02*
X635995Y133858D01*
X643307D01*
G01X668504Y121260D02*
X666929Y119685D01*
G01X645970Y395300D02*
Y399130D01*
G01X652708Y378812D02*
X648146D01*
X647623Y378289D01*
G01X659545Y375141D02*
X657273D01*
X656531Y375883D01*
X656529D01*
X653600Y378812D01*
X652708D01*
G01X676361Y377110D02*
X674304D01*
X673577Y376383D01*
X664531D01*
X663289Y375141D01*
X659545D01*
G01X647623Y378289D02*
X642907D01*
G01X669031Y388383D02*
X668937Y388289D01*
Y382565D01*
G01X649470Y395300D02*
Y390830D01*
X649460Y390820D01*
G01X655643Y389328D02*
X654151Y390820D01*
X649460D01*
G01X655643Y389328D02*
X656841Y388130D01*
X659284D01*
X663032Y384382D01*
Y382565D01*
G01X665031Y388383D02*
X666969Y386445D01*
Y382565D01*
G01X653360Y386210D02*
X655390D01*
X659035Y382565D01*
X661063D01*
G01X687581Y392383D02*
X683781D01*
G01X674843Y382565D02*
Y384098D01*
X678478Y387733D01*
X683563D01*
G01X687581Y392383D02*
Y391751D01*
X683563Y387733D01*
G01X676361Y375141D02*
X682841D01*
X684500Y376800D01*
Y377500D01*
G01X680700Y378200D02*
X683800D01*
X684500Y377500D01*
G01X687150Y385550D02*
X690500D01*
G01X691400Y391150D02*
Y386450D01*
X690500Y385550D01*
G01X675831Y392583D02*
Y390183D01*
X675031Y389383D01*
G01D02*
Y387831D01*
X672874Y385674D01*
Y382565D01*
G01X695100Y381750D02*
Y383000D01*
X695700Y383600D01*
Y385740D01*
G01D02*
Y390050D01*
G01X691400Y394650D02*
Y399250D01*
X689800Y400850D01*
G01X668217Y396181D02*
Y399969D01*
X668431Y400183D01*
G01X691400Y394650D02*
X694300D01*
X695700Y396050D01*
G01X689800Y400850D02*
X686800Y403850D01*
X675549D01*
X671882Y400183D01*
X668431D01*
G01X695700Y396050D02*
X698900D01*
X700200Y394750D01*
G01X663667Y395700D02*
Y398919D01*
X664931Y400183D01*
G01X663667Y395700D02*
Y394383D01*
X665617Y392433D01*
X668181D01*
G01X695100Y378250D02*
X700200D01*
G01X690500Y382050D02*
X684100D01*
G01X690500D02*
X691300D01*
X695100Y378250D01*
G01X684100Y382050D02*
X680350D01*
X677378Y379078D01*
X676361D01*
G01X678970Y400560D02*
X677260D01*
X675831Y399131D01*
Y396083D01*
G01X671717Y396181D02*
X675733D01*
X675831Y396083D01*
G01X671717Y396181D02*
Y392469D01*
X671681Y392433D01*
G01D02*
Y387903D01*
X670906Y387128D01*
Y382565D01*
G01X683781Y395883D02*
Y396179D01*
X679400Y400560D01*
X678970D01*
G01X653007Y382828D02*
X656757Y379078D01*
X659545D01*
G01X642907Y384289D02*
X647623D01*
G01D02*
X651546D01*
X653007Y382828D01*
G01X684769Y452153D02*
X680915D01*
X677882Y449120D01*
G01X672800Y448400D02*
X677162D01*
X677882Y449120D01*
G01X667900Y446650D02*
X669650Y448400D01*
X672800D01*
G01X689985Y441196D02*
Y443409D01*
X689394Y444000D01*
Y447528D01*
G01X689985Y441196D02*
X686096D01*
X685850Y440950D01*
G01X690000Y437000D02*
X687062D01*
X685850Y438212D01*
Y440950D01*
G01X690000Y437000D02*
Y434100D01*
X689200Y433300D01*
X686750D01*
G01X675380Y454410D02*
X679560D01*
X679862Y454712D01*
X684769D01*
G01X675380Y454410D02*
X671640D01*
G01X744833Y78995D02*
X785295D01*
X790552Y84252D01*
Y130561D01*
X789515Y131598D01*
Y188495D01*
X795033Y194013D01*
Y215415D01*
X760981Y249467D01*
X753437D01*
X748959Y253945D01*
Y269259D01*
X749620Y269920D01*
Y273620D01*
G01X712598Y140157D02*
X714173Y141732D01*
G01X729837Y428237D02*
Y425047D01*
X728720Y423930D01*
G01X700200Y391250D02*
Y388200D01*
G01Y381750D02*
Y384800D01*
G01X708355Y454712D02*
X704255D01*
G01X743480Y435640D02*
Y439080D01*
G01X706120Y437980D02*
Y441410D01*
G01X717150Y450245D02*
X713150D01*
G01D02*
Y449400D01*
X714600Y447950D01*
Y446230D01*
G01X710268Y446055D02*
X711744D01*
X711919Y446230D01*
X714600D01*
G01X710268Y446055D02*
X708550Y447773D01*
Y450950D01*
X707347Y452153D01*
X704255D01*
G01X699630Y447528D02*
Y445670D01*
X700900Y444400D01*
Y441785D01*
G01D02*
X701120Y441565D01*
Y437370D01*
G01X729837Y428237D02*
X730165Y428565D01*
Y433840D01*
G01X740900Y456400D02*
X736400D01*
G01D02*
X736130Y456130D01*
Y451570D01*
G01X735492Y447367D02*
Y450932D01*
X736130Y451570D01*
G01X734040Y441340D02*
Y444259D01*
X735492Y445711D01*
Y447367D01*
X15812Y-86244D03*
X27058Y25484D03*
X81539Y542850D03*
X116063Y14567D03*
Y39075D03*
X98425Y472441D03*
X137795D03*
X374015Y156220D03*
X389764Y460630D03*
X437008D03*
X411652Y539991D03*
X531496Y371299D03*
X596456Y116142D03*
X812711Y-86834D03*
X798456Y26432D03*
X781496Y198818D03*
G54D131*
G01X646456Y118110D02*
X643675Y119721D01*
X642849D01*
X632262Y112844D01*
X625577Y102550D01*
X605901Y89770D01*
X596820Y87842D01*
X574420Y92603D01*
X546835Y110526D01*
X522820Y147511D01*
X504913Y159139D01*
X504914D01*
X496310Y172398D01*
Y173381D01*
X496499Y173570D01*
Y175070D01*
G01X494199D02*
Y173628D01*
X494710Y173117D01*
Y171924D01*
X503756Y157982D01*
X512994Y151983D01*
X521663Y146354D01*
X533670Y127862D01*
X545678Y109369D01*
X559755Y100223D01*
X566651Y95742D01*
X573797Y91099D01*
X596820Y86206D01*
X606524Y88266D01*
X620715Y97483D01*
X622181Y97172D01*
X623414Y97973D01*
X623726Y99439D01*
X626734Y101393D01*
X633419Y111687D01*
X643307Y118109D01*
Y118110D01*
G01X646456Y121260D02*
X643638Y122864D01*
X636975D01*
X627994Y117035D01*
X619985Y104700D01*
X603920Y94260D01*
X596883Y92765D01*
X576367Y97129D01*
X550273Y114070D01*
X524473Y153810D01*
X514081Y160557D01*
Y160558D01*
X513023Y161244D01*
X505919Y172185D01*
Y173144D01*
X506245Y173470D01*
Y175012D01*
G01X643307Y121260D02*
X643303Y121264D01*
X637449D01*
Y121263D01*
X633300Y118570D01*
X629151Y115878D01*
X621143Y103543D01*
X604543Y92756D01*
X596883Y91129D01*
X575744Y95625D01*
X562448Y104258D01*
X549116Y112913D01*
X536031Y133068D01*
X523316Y152653D01*
X515664Y157621D01*
X514198Y157310D01*
X512965Y158110D01*
X512653Y159576D01*
X511866Y160087D01*
X504319Y171711D01*
Y173296D01*
X503945Y173670D01*
Y175012D01*
G01X490877Y185047D02*
Y184034D01*
G03X491005Y183725I437J0D01*
G03X491314Y183597I309J309D01*
G01X493271D01*
G02X495306Y182753I-1J-2878D01*
G01X495448Y182611D01*
G02X496149Y180922I-1688J-1691D01*
G01Y179062D01*
X496499Y178712D01*
Y177270D01*
G01X490877Y180547D02*
Y181560D01*
G02X491005Y181869I437J0D01*
G02X491314Y181997I309J-309D01*
G01X493270D01*
G02X494174Y181622I0J-1278D01*
G01X494317Y181479D01*
G02X494549Y180921I-557J-559D01*
G01Y179062D01*
X494199Y178712D01*
Y177270D01*
G01X500302Y184989D02*
Y183976D01*
G03X500430Y183667I437J0D01*
G03X500739Y183539I309J309D01*
G01X502924D01*
G02X505024Y182670I0J-2972D01*
G02X505895Y180567I-2103J-2103D01*
G01Y179004D01*
X506245Y178654D01*
Y177212D01*
G01X500302Y180489D02*
Y181502D01*
G02X500430Y181811I437J0D01*
G02X500739Y181939I309J-309D01*
G01X502924D01*
G02X503893Y181538I0J-1371D01*
G02X504295Y180567I-972J-971D01*
G01Y179004D01*
X503945Y178654D01*
Y177212D01*
G01X516370Y177154D02*
Y178596D01*
X516020Y178946D01*
Y180797D01*
G03X515234Y182695I-2685J0D01*
G03X513336Y183481I-1898J-1899D01*
G01X510864D01*
G02X510555Y183609I0J437D01*
G02X510427Y183918I309J309D01*
G01Y184931D01*
G01X514070Y177154D02*
Y178596D01*
X514420Y178946D01*
Y180797D01*
G03X514102Y181563I-1084J-1D01*
G03X513336Y181881I-767J-766D01*
G01X510864D01*
G03X510555Y181753I0J-437D01*
G03X510427Y181444I309J-309D01*
G01Y180431D01*
G01X571249Y127362D02*
X569839Y127062D01*
X569424Y127332D01*
X569062Y127254D01*
X568989Y127239D01*
X568510Y127138D01*
X566870Y127488D01*
X565645Y128281D01*
X521269Y196503D01*
X514219Y201158D01*
X512296Y203081D01*
Y203080D01*
G02X511011Y206085I3103J3104D01*
G03X510833Y206515I-608J0D01*
G03X510403Y206693I-430J-430D01*
G01X509843D01*
G01X517493Y207962D02*
X517494Y207961D01*
X518366Y206613D01*
X522035Y204231D01*
X557098Y150241D01*
X574644Y138848D01*
X574936Y138786D01*
X574937D01*
X578662Y137996D01*
X580555Y138399D01*
X581252Y137946D01*
X582353Y138181D01*
G01X519000Y212914D02*
X524573Y209282D01*
X556046Y160817D01*
X569877Y151831D01*
X570827Y151215D01*
X583449Y148529D01*
X587017Y149228D01*
X587255Y149278D01*
X587499Y149330D01*
X587913Y149060D01*
X589314Y149359D01*
G01X519873Y214255D02*
X525731Y210438D01*
X557203Y161974D01*
X562881Y158285D01*
X564347Y158597D01*
X565580Y157796D01*
X565891Y156330D01*
X567124Y155529D01*
X568590Y155840D01*
X569823Y155039D01*
X570134Y153573D01*
X571450Y152719D01*
X583462Y150163D01*
X586687Y150794D01*
X586688D01*
X587167Y150896D01*
X587434Y151309D01*
X588836Y151608D01*
G01X579993Y158187D02*
X578860Y157945D01*
X578742Y158020D01*
X576537Y157574D01*
X573714Y158173D01*
X573713D01*
X573422Y158235D01*
X556605Y169157D01*
X527859Y213425D01*
X521145Y217785D01*
G01X518561Y223303D02*
X522220D01*
X530841Y217703D01*
X554145Y181813D01*
X566266Y173945D01*
X573872Y172328D01*
X582115Y174079D01*
X582676Y173712D01*
X584086Y174012D01*
G01X518561Y224903D02*
X522695D01*
X531998Y218860D01*
X538902Y208228D01*
X540369Y207916D01*
X541169Y206683D01*
X540857Y205217D01*
X541658Y203984D01*
X543124Y203672D01*
X543924Y202439D01*
X543613Y200973D01*
X555302Y182970D01*
X566889Y175449D01*
X573872Y173964D01*
X582025Y175696D01*
X582198Y175962D01*
X583608Y176262D01*
G01X519094Y227490D02*
X520810D01*
X526460Y226290D01*
X538622Y218373D01*
X557365Y189503D01*
X566914Y183304D01*
X571574Y182313D01*
X573364Y182691D01*
X573779Y182421D01*
X575189Y182722D01*
G01X579391Y198464D02*
X577981Y198163D01*
X577634Y198388D01*
X575532Y197941D01*
X559423Y201367D01*
X556091Y203530D01*
X552720Y205716D01*
X542342Y221695D01*
X528568Y230746D01*
X525379Y231427D01*
X518969D01*
G01X578913Y200713D02*
X577503Y200413D01*
X577188Y199930D01*
X575532Y199577D01*
X560046Y202871D01*
X553877Y206874D01*
X549778Y213184D01*
X550090Y214650D01*
X549289Y215883D01*
X547823Y216194D01*
X547022Y217427D01*
X547334Y218893D01*
X546533Y220126D01*
X545067Y220437D01*
X543501Y222848D01*
X529196Y232248D01*
X525548Y233027D01*
X518969D01*
G01X583321Y214047D02*
X581910Y213746D01*
X581563Y213971D01*
X576560Y212907D01*
X574988Y213243D01*
X559141Y216611D01*
X529978Y235571D01*
X524411Y236752D01*
X520665D01*
G01X516677Y300437D02*
X518578D01*
X531816Y313675D01*
X533937D01*
X534160Y313898D01*
X535228D01*
G01X516677Y298837D02*
X519241D01*
X520757Y300353D01*
X522256D01*
X523295Y301392D01*
Y302891D01*
X532479Y312075D01*
X533831D01*
X534208Y311698D01*
X535228D01*
G01X519204Y292049D02*
X524492D01*
X531140Y298697D01*
X534047D01*
X534230Y298880D01*
X535313D01*
G01X519204Y290449D02*
X525155D01*
X526341Y291635D01*
X527841D01*
X528880Y292675D01*
Y294174D01*
X531803Y297097D01*
X533874D01*
X534291Y296680D01*
X535313D01*
G01X535048Y306421D02*
X533967D01*
X533753Y306207D01*
X531123D01*
X520828Y295912D01*
X518605D01*
G01X535300Y319400D02*
X534232D01*
X534052Y319220D01*
X528962D01*
X521775Y312033D01*
Y309524D01*
X516199Y303948D01*
X515215D01*
G01X646456Y127559D02*
X643560Y129159D01*
X641094D01*
X634815Y127826D01*
X621895Y119435D01*
X613168Y105997D01*
X602260Y98915D01*
X596765Y97745D01*
X578282Y101673D01*
X556141Y116056D01*
X530398Y155710D01*
X523988Y159872D01*
X516147Y171945D01*
Y173189D01*
X516370Y173412D01*
Y174954D01*
G01X643307Y127559D02*
X641263D01*
X639806Y127249D01*
X637621Y126785D01*
X636528Y126553D01*
X635437Y126322D01*
X623052Y118278D01*
X614325Y104840D01*
X602883Y97411D01*
X596765Y96109D01*
X577659Y100169D01*
X571874Y103927D01*
X566339Y107523D01*
X554983Y114899D01*
X543605Y132427D01*
X532411Y149669D01*
X530945Y149981D01*
X530118Y151256D01*
X530430Y152722D01*
X529241Y154553D01*
X522831Y158715D01*
X514547Y171471D01*
Y173135D01*
X514070Y173612D01*
Y174954D01*
G01X646456Y130708D02*
X643599Y132308D01*
X638674D01*
X626425Y129716D01*
X618714Y124708D01*
X618715Y124707D01*
X608204Y108526D01*
X600489Y103519D01*
X596628Y102696D01*
X582427Y105717D01*
X578082Y107745D01*
X559833Y119597D01*
X526245Y171335D01*
Y173104D01*
X526495Y173354D01*
Y174896D01*
G01X643307Y130708D02*
X638842D01*
X627047Y128212D01*
X619874Y123552D01*
X619873Y123551D01*
X609361Y107368D01*
X601112Y102015D01*
X596628Y101060D01*
X581915Y104189D01*
X579577Y105281D01*
X577304Y106342D01*
X558676Y118440D01*
X527536Y166407D01*
X526070Y166719D01*
X525270Y167952D01*
X525581Y169419D01*
X524645Y170861D01*
Y173104D01*
X524195Y173554D01*
Y174896D01*
G01X570771Y129612D02*
X569361Y129312D01*
X569089Y128898D01*
X569088Y128897D01*
X568800Y128835D01*
X568513Y128774D01*
X567493Y128992D01*
X566801Y129440D01*
X565999Y130672D01*
X566310Y132139D01*
X565508Y133371D01*
X564042Y133682D01*
X563240Y134914D01*
X563551Y136381D01*
X562749Y137613D01*
X561283Y137924D01*
X560481Y139156D01*
X560829Y140798D01*
X560027Y142030D01*
X558387Y142377D01*
X522429Y197655D01*
X515236Y202404D01*
X513428Y204212D01*
G02X512611Y206184I1971J1972D01*
G02X512760Y206544I509J0D01*
G02X513120Y206693I360J-360D01*
G01X513780D01*
G01X518835Y208834D02*
X519530Y207767D01*
X523192Y205388D01*
X558255Y151398D01*
X562534Y148620D01*
X564000Y148931D01*
X565233Y148131D01*
X565545Y146665D01*
X566778Y145864D01*
X568244Y146175D01*
X569477Y145375D01*
X569789Y143909D01*
X571022Y143108D01*
X572488Y143419D01*
X573721Y142619D01*
X574033Y141153D01*
X575266Y140352D01*
X575268D01*
X578661Y139632D01*
X580379Y139998D01*
X580465Y140130D01*
X581875Y140430D01*
G01X579515Y160436D02*
X578464Y160211D01*
X578004Y159504D01*
X576545Y159209D01*
X574044Y159739D01*
X568608Y163270D01*
Y163271D01*
X568296Y164737D01*
X567063Y165538D01*
X565597Y165226D01*
X564364Y166027D01*
X564052Y167493D01*
X562820Y168293D01*
X561353Y167982D01*
X557762Y170314D01*
X529016Y214582D01*
X522017Y219127D01*
G01X572923Y130070D02*
X573763Y130258D01*
X574360Y129943D01*
X575795Y130238D01*
X575811Y130241D01*
G03X576151Y130794I-90J436D01*
G01X575932Y131783D01*
G01X646456Y137008D02*
X643307Y138608D01*
X641974D01*
X640866Y137500D01*
X633023D01*
X614627Y141410D01*
X606068Y146967D01*
X600227Y155960D01*
X595624Y177616D01*
X599825Y197364D01*
X594798Y221012D01*
X592695Y224250D01*
X587095Y227887D01*
X580916Y229200D01*
X565857D01*
X565507Y229550D01*
X564065D01*
G01Y227250D02*
X565507D01*
X565857Y227600D01*
X580747D01*
X583610Y226991D01*
Y226990D01*
X586473Y226383D01*
X591538Y223093D01*
X593294Y220389D01*
X598189Y197364D01*
X596830Y190977D01*
X595573Y190161D01*
X595267Y188723D01*
X596083Y187466D01*
X595777Y186028D01*
X594520Y185212D01*
X594214Y183774D01*
X595030Y182517D01*
X593988Y177616D01*
X596170Y167350D01*
X595354Y166093D01*
X595659Y164655D01*
X596916Y163839D01*
X597222Y162401D01*
X596405Y161143D01*
X596711Y159706D01*
X597968Y158889D01*
X598723Y155337D01*
X604911Y145810D01*
X614004Y139906D01*
X632854Y135900D01*
X641529D01*
X642637Y137008D01*
X643307D01*
G01Y140157D02*
X641660D01*
X640503Y139000D01*
X635882D01*
X633128Y140788D01*
X615787Y144476D01*
X608355Y149303D01*
X603296Y157092D01*
X598961Y177458D01*
X603737Y199912D01*
X603431Y201350D01*
X602174Y202166D01*
X601869Y203604D01*
X602685Y204862D01*
X602380Y206299D01*
X601123Y207116D01*
X600817Y208554D01*
X601634Y209811D01*
X601328Y211249D01*
X600071Y212066D01*
X599766Y213503D01*
X600582Y214761D01*
X599114Y221670D01*
X594859Y228222D01*
X586980Y233340D01*
X580108Y234800D01*
X573838Y236338D01*
X571943D01*
X570883Y235278D01*
X569413D01*
X568353Y236338D01*
X564222D01*
X563872Y235988D01*
X562430D01*
G01X520552Y184873D02*
Y183860D01*
G03X520680Y183551I437J0D01*
G03X520989Y183423I309J309D01*
G01X523163D01*
G02X525272Y182549I0J-2982D01*
G02X526145Y180441I-2109J-2108D01*
G01Y178888D01*
X526495Y178538D01*
Y177096D01*
G01X520552Y180373D02*
Y181386D01*
G02X520680Y181695I437J0D01*
G02X520989Y181823I309J-309D01*
G01X523163D01*
G02X524140Y181418I0J-1381D01*
G02X524545Y180441I-976J-977D01*
G01Y178888D01*
X524195Y178538D01*
Y177096D01*
G01X561865Y229550D02*
X561515Y229200D01*
X552948D01*
G02X552313Y229463I0J898D01*
G02X552050Y230098I635J635D01*
G01Y231403D01*
G02X552196Y231754I497J-1D01*
G01X552197Y231755D01*
G02X552545Y231900I348J-345D01*
G01X553500D01*
G01X561865Y227250D02*
X561515Y227600D01*
X552948D01*
G02X551181Y228331I-1J2499D01*
G02X550450Y230098I1768J1766D01*
G01Y231407D01*
G03X550306Y231755I-493J0D01*
G03X549956Y231900I-350J-350D01*
G01X549000D01*
G01X560230Y235988D02*
X559880Y236338D01*
X551313D01*
G02X549546Y237069I-1J2499D01*
G02X548815Y238836I1768J1766D01*
G01Y240145D01*
G03X548671Y240493I-492J0D01*
G03X548321Y240638I-350J-350D01*
G01X547365D01*
G01X519094Y229090D02*
X520979D01*
X527084Y227794D01*
X539780Y219530D01*
X546863Y208620D01*
X553012Y199148D01*
X554478Y198836D01*
X555279Y197603D01*
X554967Y196137D01*
X555767Y194904D01*
X557233Y194592D01*
X558034Y193359D01*
X557722Y191893D01*
X558522Y190660D01*
X565285Y186270D01*
Y186271D01*
X567537Y184808D01*
X571576Y183949D01*
X573031Y184256D01*
X573301Y184671D01*
X574711Y184971D01*
G01X582842Y216296D02*
X581432Y215996D01*
X581119Y215514D01*
X576561Y214544D01*
X574984Y214880D01*
X574168Y216137D01*
X572730Y216443D01*
X571473Y215626D01*
X570035Y215932D01*
X569219Y217189D01*
X567781Y217495D01*
X566524Y216678D01*
X559765Y218115D01*
X530601Y237075D01*
X524582Y238352D01*
X520665D01*
G01X646456Y140157D02*
X643717Y141757D01*
X640997D01*
X639840Y140600D01*
X636356D01*
X633751Y142292D01*
X616410Y145980D01*
X609512Y150460D01*
X604800Y157715D01*
X600597Y177458D01*
X605373Y199912D01*
X600618Y222293D01*
X596016Y229379D01*
X587603Y234844D01*
X580465Y236360D01*
X574032Y237938D01*
X564222D01*
X563872Y238288D01*
X562430D01*
G01X646456Y146456D02*
X644027Y148056D01*
X635000D01*
X616122Y152080D01*
X614439Y153174D01*
Y153173D01*
X612753Y154268D01*
X609380Y159461D01*
X605580Y177340D01*
X610374Y199896D01*
X605233Y224080D01*
X598697Y234148D01*
X587187Y241621D01*
X572150Y245509D01*
X563332D01*
X562982Y245859D01*
X561540D01*
G01X643307Y146456D02*
X634831D01*
X630345Y147412D01*
X629087Y146596D01*
X627650Y146902D01*
X626834Y148160D01*
X625396Y148466D01*
X624138Y147651D01*
X622701Y147957D01*
X621885Y149215D01*
X620447Y149521D01*
X619189Y148706D01*
X617752Y149012D01*
X616936Y150270D01*
X616929Y150272D01*
X615499Y150576D01*
X611596Y153111D01*
X607876Y158838D01*
X603944Y177340D01*
X604014Y177673D01*
X604015D01*
X608738Y199896D01*
X603729Y223457D01*
X597540Y232991D01*
X586534Y240137D01*
X571946Y243909D01*
X568569D01*
X567509Y242849D01*
X566039D01*
X564979Y243909D01*
X563332D01*
X562982Y243559D01*
X561540D01*
G01X563219Y253446D02*
X563553Y253112D01*
X568102D01*
X568167Y253047D01*
X585467Y249368D01*
X601669Y238846D01*
X611336Y223959D01*
X615503Y204269D01*
X615504Y204265D01*
X615879Y202499D01*
X610501Y177243D01*
X613889Y161317D01*
X615709Y158517D01*
X617409Y157413D01*
X617410D01*
X617977Y157045D01*
X637079Y152985D01*
X639817Y151206D01*
X643596D01*
X646456Y149606D01*
G01X563219Y251146D02*
X563585Y251512D01*
X567693D01*
X569131Y251206D01*
X569947Y249949D01*
X571385Y249643D01*
X572642Y250459D01*
X574080Y250153D01*
X574896Y248896D01*
X576334Y248590D01*
X577591Y249406D01*
X584844Y247864D01*
X592677Y242776D01*
X600329Y237807D01*
X600512Y237689D01*
X609832Y223337D01*
X611099Y217349D01*
X610282Y216093D01*
X610586Y214654D01*
X611842Y213837D01*
X612147Y212399D01*
X611329Y211142D01*
X611634Y209704D01*
X612890Y208887D01*
X612889D01*
X614242Y202498D01*
X608865Y177243D01*
X612385Y160694D01*
X614552Y157359D01*
X617354Y155541D01*
X627195Y153450D01*
X636456Y151481D01*
X639342Y149606D01*
X643307D01*
G01X560230Y238288D02*
X559880Y237938D01*
X551313D01*
G02X550678Y238201I0J898D01*
G02X550415Y238836I635J635D01*
G01Y240141D01*
G02X550561Y240492I497J-1D01*
G01X550562Y240493D01*
G02X550910Y240638I348J-345D01*
G01X551865D01*
G01X559340Y245859D02*
X558990Y245509D01*
X550423D01*
G02X549788Y245772I0J898D01*
G02X549525Y246407I635J635D01*
G01Y247712D01*
G02X549671Y248063I497J-1D01*
G01X549672Y248064D01*
G02X550020Y248209I348J-345D01*
G01X550975D01*
G01X559340Y243559D02*
X558990Y243909D01*
X550423D01*
G02X548656Y244640I-1J2499D01*
G02X547925Y246407I1768J1766D01*
G01Y247716D01*
G03X547781Y248064I-493J0D01*
G03X547431Y248209I-350J-350D01*
G01X546475D01*
G01X561019Y253446D02*
X560105D01*
X559755Y253096D01*
X550165D01*
G02X549530Y253359I0J898D01*
G02X549267Y253994I635J635D01*
G01Y255299D01*
G02X549413Y255650I497J-1D01*
G01X549414Y255651D01*
G02X549762Y255796I348J-345D01*
G01X550717D01*
G01X561019Y251146D02*
X560106D01*
X559756Y251496D01*
X550165D01*
G02X548398Y252227I-1J2499D01*
G02X547667Y253994I1768J1766D01*
G01Y255303D01*
G03X547523Y255651I-493J0D01*
G03X547173Y255796I-350J-350D01*
G01X546217D01*
G01X537513Y298880D02*
X537813Y298580D01*
X545745D01*
G03X546380Y298843I0J898D01*
G03X546643Y299478I-635J635D01*
G01Y300783D01*
G03X546497Y301134I-497J-1D01*
G01X546496Y301135D01*
G03X546148Y301280I-348J-345D01*
G01X545193D01*
G01X537513Y296680D02*
X537813Y296980D01*
X545745D01*
G03X547512Y297711I1J2499D01*
G03X548243Y299478I-1768J1766D01*
G01Y300787D01*
G02X548387Y301135I492J0D01*
G02X548737Y301280I350J-350D01*
G01X549693D01*
G01X535048Y304221D02*
X534041D01*
X533655Y304607D01*
X531786D01*
X525290Y298111D01*
Y296612D01*
X524251Y295572D01*
X522751D01*
X521491Y294312D01*
X518605D01*
G01X545278Y315738D02*
X546233D01*
G02X546581Y315593I0J-490D01*
G01X546582Y315592D01*
G02X546728Y315241I-351J-352D01*
G01Y313999D01*
G02X546610Y313716I-401J1D01*
G02X546327Y313598I-284J283D01*
G01X539220D01*
X538920Y313898D01*
X537428D01*
G01X549778Y315738D02*
X548822D01*
G03X548472Y315593I0J-495D01*
G03X548328Y315245I348J-348D01*
G01Y313999D01*
G02X547742Y312584I-2001J0D01*
G02X546327Y311998I-1415J1415D01*
G01X539220D01*
X538920Y311698D01*
X537428D01*
G01X537500Y319400D02*
X538992D01*
X539189Y319203D01*
X540256D01*
X542402Y321349D01*
X547179D01*
G03X547814Y321612I0J898D01*
G03X548077Y322247I-635J635D01*
G01Y323552D01*
G03X547931Y323903I-497J-1D01*
G01X547930Y323904D01*
G03X547582Y324049I-348J-345D01*
G01X546627D01*
G01X537500Y317200D02*
X538992D01*
X539395Y317603D01*
X540919D01*
X543065Y319749D01*
X547179D01*
G03X548946Y320481I0J2499D01*
G01X548947D01*
G03X549677Y322247I-1769J1765D01*
G01Y323556D01*
G02X549821Y323904I492J0D01*
G02X550171Y324049I350J-350D01*
G01X551127D01*
G01X537248Y306421D02*
X537737D01*
X538021Y306137D01*
X545839D01*
G03X546671Y306969I0J832D01*
G01Y308274D01*
G03X546525Y308625I-497J-1D01*
G01X546524Y308626D01*
G03X546176Y308771I-348J-345D01*
G01X545221D01*
G01X549721D02*
X548765D01*
G03X548415Y308626I0J-495D01*
G03X548271Y308278I349J-348D01*
G01Y306969D01*
G02X545839Y304537I-2432J0D01*
G01X538153D01*
X537837Y304221D01*
X537248D01*
G01X535300Y317200D02*
X534280D01*
X533860Y317620D01*
X529625D01*
X526953Y314948D01*
Y313449D01*
X525914Y312409D01*
X524414D01*
X523375Y311370D01*
Y308861D01*
X516862Y302348D01*
X515215D01*
G01X573401Y127820D02*
X574374Y128007D01*
X574666Y128372D01*
X574682Y128375D01*
X575974Y128641D01*
G02X576655Y128371I135J-654D01*
G01X576868Y127381D01*
G01X588070Y138220D02*
X587857Y139210D01*
G03X587176Y139480I-546J-384D01*
G01X586682Y139378D01*
X585633Y139142D01*
X585427Y138830D01*
X584505Y138639D01*
G01X584027Y140888D02*
X585036Y141097D01*
X585544Y140764D01*
X586332Y140940D01*
X586344Y140943D01*
X586345D01*
X586997Y141077D01*
X587013Y141080D01*
G03X587353Y141633I-90J436D01*
G01X587134Y142622D01*
G01X595402Y149579D02*
X595189Y150569D01*
G03X594667Y150853I-427J-164D01*
G01X594500Y150817D01*
X593134Y150528D01*
X592867Y150115D01*
X591466Y149817D01*
G01X590988Y152066D02*
X592343Y152355D01*
X592758Y152085D01*
X594407Y152434D01*
Y152435D01*
G03X594685Y152992I-83J389D01*
G01X594466Y153981D01*
G01X586081Y158407D02*
X585868Y159397D01*
G03X585346Y159681I-427J-164D01*
G01X585179Y159645D01*
X583813Y159356D01*
X583546Y158943D01*
X582145Y158645D01*
G01X585145Y162809D02*
X585364Y161820D01*
G02X585086Y161263I-361J-168D01*
G01Y161262D01*
X585012Y161246D01*
X584947Y161233D01*
X583437Y160913D01*
X583022Y161183D01*
X581667Y160894D01*
G01X586238Y174470D02*
X587193Y174667D01*
X587588Y175039D01*
X588812Y175291D01*
G02X589493Y175021I135J-654D01*
G01X589706Y174031D01*
G01X585760Y176720D02*
X586781Y176931D01*
X587243Y176603D01*
X588633Y176888D01*
X588649Y176891D01*
G03X588989Y177444I-90J436D01*
G01X588770Y178433D01*
G01X580885Y182859D02*
X580672Y183849D01*
G03X579991Y184119I-546J-384D01*
G01X578699Y183853D01*
X578683Y183850D01*
X578314Y183367D01*
X577341Y183180D01*
G01X576863Y185429D02*
X577704Y185618D01*
X578377Y185421D01*
X579812Y185716D01*
X579828Y185719D01*
G03X580168Y186272I-90J436D01*
G01X579949Y187261D01*
G01X581543Y198922D02*
X582516Y199109D01*
X582808Y199474D01*
X582824Y199477D01*
X584116Y199743D01*
G02X584797Y199473I135J-654D01*
G01X585010Y198483D01*
G01X581065Y201171D02*
X581906Y201360D01*
X582502Y201045D01*
X583937Y201340D01*
X583953Y201343D01*
G03X584293Y201896I-90J436D01*
G01X584074Y202885D01*
G01X589135Y214107D02*
X588922Y215097D01*
G03X588241Y215367I-546J-384D01*
G01X586617Y215033D01*
X586330Y214673D01*
X585473Y214505D01*
G01X588199Y218509D02*
X588418Y217520D01*
G02X588078Y216967I-430J-117D01*
G01X588062Y216964D01*
X586438Y216630D01*
X585847Y216943D01*
X584994Y216754D01*
G01X654330Y116535D02*
X652756Y118109D01*
Y118110D01*
G01X655905Y121260D02*
X654330Y119685D01*
G01X652756Y121260D02*
X654330Y122834D01*
G01X655905Y127559D02*
X657480Y125984D01*
G01X652756Y127559D02*
X654331Y125984D01*
G01X654330Y129134D02*
X655904Y130708D01*
X655905D01*
G01X654330Y132283D02*
X652756Y130709D01*
Y130708D01*
G01X655905Y137008D02*
X654330Y135433D01*
G01X652756Y137008D02*
X651181Y135433D01*
G01X655905Y140157D02*
X654330Y138582D01*
G01Y141732D02*
X652756Y140158D01*
Y140157D01*
G01X654330Y144882D02*
X655904Y146456D01*
X655905D01*
G01X651181Y144882D02*
X652755Y146456D01*
X652756D01*
G01X655905Y149606D02*
X654330Y148031D01*
G01Y151181D02*
X652756Y149607D01*
Y149606D01*
G54D122*
G01X94488Y480807D02*
Y489888D01*
G01X629400Y405234D02*
Y414324D01*
G54D113*
X694512Y457271D03*
G54D20*
X26500Y156700D03*
X49700Y394600D03*
X242733Y66711D03*
X223995Y66691D03*
X226200Y404600D03*
X275500Y405700D03*
X344891Y206040D03*
X691400Y391100D03*
X652200Y366500D03*
X757488Y297561D03*
X713150Y450195D03*
X778440Y278610D03*
X786560Y324630D03*
G54D11*
X15364Y5500D03*
X10364D03*
X5500Y10384D03*
Y15384D03*
Y20384D03*
Y25384D03*
Y30384D03*
Y35384D03*
Y40384D03*
Y45384D03*
Y50384D03*
Y55384D03*
Y60384D03*
Y65384D03*
Y70384D03*
Y75384D03*
Y80384D03*
Y85384D03*
Y90384D03*
Y95384D03*
Y100384D03*
Y105384D03*
Y110384D03*
Y115384D03*
Y120384D03*
Y125384D03*
Y130384D03*
Y135384D03*
Y140384D03*
Y145384D03*
Y150384D03*
Y155384D03*
Y160384D03*
Y165384D03*
Y170384D03*
Y175384D03*
Y180384D03*
Y185384D03*
Y190384D03*
Y195384D03*
Y200384D03*
Y205384D03*
Y210384D03*
Y215384D03*
Y220384D03*
Y225384D03*
Y230384D03*
Y235384D03*
Y240384D03*
Y245384D03*
Y250384D03*
Y255384D03*
Y260384D03*
Y265384D03*
Y270384D03*
Y275384D03*
Y280384D03*
Y285384D03*
Y290384D03*
Y295384D03*
Y300384D03*
Y305384D03*
Y310384D03*
Y315384D03*
Y320384D03*
Y325384D03*
Y330384D03*
Y335384D03*
Y340384D03*
Y345384D03*
Y350384D03*
Y355384D03*
Y360384D03*
Y365384D03*
Y370384D03*
Y375384D03*
Y380384D03*
Y385384D03*
Y390384D03*
Y395384D03*
Y400384D03*
Y405384D03*
Y410384D03*
Y415384D03*
Y420384D03*
Y425384D03*
Y430384D03*
Y435384D03*
Y440384D03*
Y445384D03*
Y450384D03*
Y455384D03*
Y460384D03*
Y465384D03*
Y470384D03*
Y475384D03*
Y480384D03*
Y485384D03*
Y530384D03*
Y525384D03*
Y520384D03*
Y515384D03*
Y510384D03*
Y505384D03*
Y490384D03*
Y495384D03*
Y500384D03*
Y535384D03*
Y540384D03*
Y545384D03*
Y550384D03*
Y555384D03*
Y560384D03*
X10266Y565366D03*
X15266D03*
X75364Y5500D03*
X70364D03*
X65364D03*
X60364D03*
X55364D03*
X50364D03*
X45364D03*
X40364D03*
X35364D03*
X30364D03*
X25364D03*
X20364D03*
X75119Y111166D03*
X20266Y565366D03*
X25266D03*
X30266D03*
X35266D03*
X40266D03*
X45266D03*
X50266D03*
X55266D03*
X60266D03*
X65266D03*
X70266D03*
X75266D03*
X95364Y5500D03*
X90364D03*
X85364D03*
X80364D03*
X105619Y111166D03*
X81119D03*
X87619D03*
X93619D03*
X99619D03*
X128580Y170810D03*
X122984Y170984D03*
X123200Y175800D03*
X125741Y166309D03*
X128459Y175658D03*
X140000Y204950D03*
X94080Y448470D03*
X80266Y565366D03*
X85266D03*
X90266D03*
X95266D03*
X100266D03*
X105266D03*
X110266D03*
X115266D03*
X120266D03*
X125266D03*
X130266D03*
X135266D03*
X200364Y5500D03*
X195364D03*
X190364D03*
X185364D03*
X180364D03*
X175364D03*
X170364D03*
X192830Y170500D03*
X197630D03*
X192830Y165700D03*
X197630D03*
X192830Y160900D03*
X197630D03*
X170900Y160500D03*
X151500D03*
X156300D03*
X161100D03*
X165900D03*
X198557Y153196D03*
X191900Y196100D03*
X196900D03*
X201700D03*
X196900Y200900D03*
X191900D03*
X196900Y205700D03*
X191900D03*
X196900Y210500D03*
X191900D03*
X201700Y205700D03*
Y200900D03*
X151500Y205000D03*
X156300D03*
X161100D03*
X165900D03*
X170900D03*
X178450Y203150D03*
X144800Y204950D03*
X177850Y324800D03*
X174995Y353588D03*
Y358388D03*
X165195D03*
X169995D03*
Y353588D03*
X197718Y350937D03*
Y355859D03*
X157650Y418100D03*
X160400Y422900D03*
X160550Y414100D03*
X177468Y417900D03*
X142865Y424021D03*
X143608Y415900D03*
X158067Y378857D03*
X160400Y427700D03*
Y432500D03*
X176311Y445493D03*
X176423Y440472D03*
X177421Y432909D03*
X177532Y426134D03*
X145392Y445207D03*
X145456Y440338D03*
X142991Y430900D03*
X200266Y565366D03*
X195266D03*
X190266D03*
X185266D03*
X180266D03*
X175266D03*
X140266D03*
X145266D03*
X150266D03*
X155266D03*
X160266D03*
X165266D03*
X170266D03*
X260364Y5500D03*
X255364D03*
X250364D03*
X245364D03*
X240364D03*
X235364D03*
X230364D03*
X225364D03*
X220364D03*
X215364D03*
X210364D03*
X205364D03*
X222700Y149300D03*
X227500D03*
X222700Y144500D03*
X227500D03*
X222700Y139700D03*
X227500D03*
X222700Y158900D03*
X227500D03*
X222700Y154100D03*
X227500D03*
X202430Y170500D03*
Y165700D03*
Y160900D03*
X253600Y139500D03*
Y134700D03*
X251800Y153600D03*
Y144000D03*
Y148800D03*
X258400Y134700D03*
Y139500D03*
X263200Y134700D03*
Y139500D03*
X222800Y204600D03*
X227600D03*
X222800Y219000D03*
X227600D03*
X222800Y214200D03*
X227600D03*
X222800Y209400D03*
X227600D03*
X222490Y235373D03*
X227290D03*
X222246Y229952D03*
X227046D03*
X222800Y223800D03*
X227600D03*
X253600Y230500D03*
Y225700D03*
Y220900D03*
X258400Y230500D03*
Y225700D03*
Y220900D03*
X263200Y230500D03*
Y225700D03*
Y220900D03*
X222460Y240264D03*
X227260D03*
X249204Y244103D03*
X254300Y357732D03*
X222818Y364806D03*
X222909Y371864D03*
X223000Y378246D03*
X246700Y418600D03*
X209052Y470198D03*
X213700Y448450D03*
X208900D03*
X203000Y451300D03*
X204252Y470198D03*
X204364Y478917D03*
X209164D03*
X212589Y494694D03*
X220589D03*
X216589Y489694D03*
X208589D03*
X224589D03*
X205266Y565366D03*
X210266D03*
X215266D03*
X220266D03*
X225266D03*
X230266D03*
X235266D03*
X240266D03*
X245266D03*
X250266D03*
X255266D03*
X260266D03*
X325364Y5500D03*
X320364D03*
X315364D03*
X310364D03*
X305364D03*
X300364D03*
X295364D03*
X290364D03*
X285364D03*
X280364D03*
X275364D03*
X270364D03*
X265364D03*
X295960Y148987D03*
Y154387D03*
X308907Y171800D03*
Y166400D03*
Y161000D03*
X287000Y117600D03*
Y125000D03*
X285500Y130400D03*
X290300D03*
X287300Y173000D03*
X292100D03*
X295650Y169554D03*
X295100Y130400D03*
X272800Y168000D03*
Y172800D03*
Y134700D03*
X268000Y165962D03*
X268064Y171792D03*
X268000Y158700D03*
Y153900D03*
Y134700D03*
Y139500D03*
Y144300D03*
Y149100D03*
X296200Y195900D03*
Y190500D03*
X308907Y215200D03*
Y220600D03*
Y226000D03*
Y231400D03*
Y236800D03*
Y209800D03*
Y188200D03*
Y199000D03*
Y204400D03*
Y177200D03*
Y193600D03*
Y182800D03*
X296400Y237950D03*
Y232550D03*
X295801Y210294D03*
X292600Y214500D03*
X287800D03*
X272800Y177600D03*
X268064Y184062D03*
X268000Y235300D03*
Y230500D03*
Y225700D03*
Y220900D03*
Y216000D03*
Y211200D03*
X268118Y191305D03*
X268000Y206400D03*
Y196800D03*
Y201600D03*
Y178062D03*
X308907Y242200D03*
X295879Y255540D03*
X291079D03*
X286279D03*
X266404Y249707D03*
X268000Y244900D03*
Y240100D03*
X276070Y395357D03*
X265266Y565366D03*
X270266D03*
X275266D03*
X280266D03*
X285266D03*
X290266D03*
X295266D03*
X300266D03*
X305266D03*
X310266D03*
X315266D03*
X320266D03*
X325266D03*
X330364Y5500D03*
X353556Y257143D03*
X353500Y262500D03*
X346700Y296333D03*
Y291533D03*
X350586Y495815D03*
X355523Y495025D03*
X360461Y494236D03*
X365398Y493446D03*
X370335Y492656D03*
X375272Y491866D03*
X380210Y491077D03*
X385169Y490563D03*
X329156Y545492D03*
Y540492D03*
Y535492D03*
Y530492D03*
Y525492D03*
Y520492D03*
Y515492D03*
Y560492D03*
Y555492D03*
Y550492D03*
X432200Y341500D03*
X421375Y346552D03*
X421357Y341201D03*
X405169Y490563D03*
X410169D03*
X415169D03*
X420169D03*
X425169D03*
X430169D03*
X435169D03*
X440169D03*
X445146Y490850D03*
X450083Y491640D03*
X390169Y490563D03*
X395169D03*
X400169D03*
X465300Y351481D03*
X455900Y341100D03*
X493200Y347700D03*
X485500Y432820D03*
X490800D03*
X485500Y427520D03*
X490800D03*
Y443420D03*
X485500D03*
Y438120D03*
X490800D03*
X505500Y464400D03*
Y469200D03*
Y474000D03*
X509500Y450800D03*
Y446000D03*
Y441200D03*
X469832Y494799D03*
X474769Y495589D03*
X455020Y492430D03*
X459958Y493219D03*
X464895Y494009D03*
X497636Y515532D03*
Y520532D03*
Y525532D03*
Y530532D03*
Y535532D03*
Y540532D03*
Y545532D03*
Y550532D03*
Y555532D03*
Y560532D03*
X502550Y565366D03*
X507550D03*
X512550D03*
X570234Y298026D03*
X572634Y293526D03*
X518020Y343632D03*
X523602Y345779D03*
X528902Y341725D03*
X571300Y414800D03*
X567200Y407700D03*
X572062Y384378D03*
X527742Y425481D03*
X522942D03*
X518142D03*
X527742Y432481D03*
X522942D03*
X518142D03*
X529500Y471500D03*
X551400Y437800D03*
X545900D03*
X539800Y437900D03*
X517550Y565366D03*
X522550D03*
X527550D03*
X532550D03*
X537550D03*
X542550D03*
X547550D03*
X552550D03*
X557550D03*
X562550D03*
X567550D03*
X572550D03*
X591446Y6545D03*
X596446D03*
X601446D03*
X606446D03*
X611446D03*
X616446D03*
X621446D03*
X636446D03*
X631446D03*
X626446D03*
X576797Y113877D03*
X582554Y116361D03*
X575134Y298026D03*
X577534Y293526D03*
X580034Y298026D03*
X580900Y414800D03*
X576100D03*
X632150Y389100D03*
X576862Y384378D03*
X581087Y379569D03*
X576287D03*
X581692Y384378D03*
X628113Y428617D03*
X623313D03*
X618513D03*
X613713D03*
X605534Y480027D03*
X635000Y427784D03*
X619600Y446100D03*
X629200D03*
X624400D03*
X577550Y565366D03*
X582550D03*
X587550D03*
X592550D03*
X597550D03*
X602550D03*
X607550D03*
X612550D03*
X617550D03*
X622550D03*
X627550D03*
X632550D03*
X641446Y6545D03*
X646446D03*
X651446D03*
X696446D03*
X691446D03*
X661446D03*
X656446D03*
X686446D03*
X681446D03*
X676446D03*
X671446D03*
X666446D03*
X655964Y52248D03*
X678500Y227500D03*
X695600D03*
X686900D03*
X682700Y223300D03*
X691721D03*
X646318Y217778D03*
X671508Y220824D03*
X650684Y221630D03*
X654464Y217358D03*
X661452Y217241D03*
X664452Y222315D03*
X657920Y221560D03*
X641579Y221770D03*
X667166Y217194D03*
X675264Y216982D03*
X675136Y268500D03*
X637705Y298765D03*
X642705D03*
X659977Y323082D03*
X664731Y324099D03*
X660115Y351977D03*
Y356777D03*
X664731Y343299D03*
X655500Y360000D03*
X660115Y361577D03*
X664731Y338499D03*
Y333699D03*
Y328899D03*
X659977Y342282D03*
Y332682D03*
Y347082D03*
Y337482D03*
Y327882D03*
X696900Y337800D03*
X697500Y358200D03*
X637705Y303765D03*
X642705D03*
X674700Y306300D03*
X679500D03*
Y311100D03*
X674700D03*
X679500Y315900D03*
X674700D03*
X665520Y307707D03*
Y312507D03*
X654642D03*
X654488Y317417D03*
X660100Y307500D03*
X654642Y307707D03*
X665478Y317527D03*
X684400Y400100D03*
X637550Y389050D03*
X655532Y425245D03*
X658032Y420245D03*
X653032D03*
X653200Y408800D03*
X694950Y477850D03*
Y473050D03*
X688500Y484400D03*
X675700Y468000D03*
Y463500D03*
X675400Y472300D03*
X659000Y428900D03*
X652200Y429100D03*
X639120Y462230D03*
X688500Y488600D03*
X637550Y565366D03*
X642550D03*
X647550D03*
X652550D03*
X657550D03*
X662550D03*
X667550D03*
X672550D03*
X677550D03*
X682550D03*
X687550D03*
X692550D03*
X697550D03*
X701446Y6545D03*
X748500Y109750D03*
X754000Y109600D03*
X726039Y84955D03*
X759023Y97440D03*
X737100Y95600D03*
X760100Y130900D03*
X749200Y126250D03*
X755300Y131150D03*
X754000Y126250D03*
X760450Y119550D03*
X750400Y131050D03*
X701500Y219000D03*
X707000Y217500D03*
X748644Y191051D03*
X701500Y225500D03*
X742200Y340800D03*
Y345600D03*
X737400Y340800D03*
Y345600D03*
X732600Y331200D03*
Y336000D03*
Y340800D03*
Y355200D03*
Y350400D03*
Y345600D03*
X701100Y315900D03*
X705900D03*
X701100Y311100D03*
X705900D03*
Y306300D03*
X701100D03*
X714600Y338900D03*
Y348500D03*
Y343700D03*
X709800Y348500D03*
Y343700D03*
X706500Y337800D03*
X701700D03*
X707100Y358200D03*
X702300D03*
X704115Y414466D03*
Y409666D03*
Y404866D03*
Y400066D03*
X722100Y368300D03*
X717300D03*
X712500D03*
X742200Y380400D03*
Y370800D03*
Y375600D03*
X728700Y381000D03*
Y376200D03*
Y371400D03*
X722100Y363500D03*
X717300D03*
X712500D03*
X705900Y386900D03*
X711000Y395100D03*
X710900Y386800D03*
X706000Y395100D03*
X725247Y458974D03*
X724422Y464139D03*
X724400Y485200D03*
Y480400D03*
Y475600D03*
X740900Y476400D03*
Y469400D03*
Y461900D03*
X704340Y468062D03*
X705400Y477400D03*
X724400Y490200D03*
X702550Y565366D03*
X707550D03*
X712550D03*
X717550D03*
X722550D03*
X727550D03*
X732550D03*
X737550D03*
X742550D03*
X747550D03*
X752550D03*
X757550D03*
X821272Y49340D03*
Y44340D03*
Y39340D03*
Y34340D03*
Y29340D03*
Y24340D03*
Y19340D03*
Y14340D03*
Y9340D03*
X815364Y5500D03*
X810364D03*
X805364D03*
X800364D03*
X795364D03*
X790364D03*
X785364D03*
X780364D03*
X775364D03*
X770364D03*
X765364D03*
X821272Y114340D03*
Y109340D03*
Y104340D03*
Y99340D03*
Y94340D03*
Y89340D03*
Y84340D03*
Y79340D03*
Y74340D03*
Y69340D03*
Y64340D03*
Y59340D03*
Y54340D03*
X760500Y126000D03*
X764900Y130800D03*
X765500Y119500D03*
X763500Y115000D03*
X765800Y125800D03*
X821272Y174340D03*
Y169340D03*
Y164340D03*
Y159340D03*
Y154340D03*
Y149340D03*
Y144340D03*
Y139340D03*
Y134340D03*
Y129340D03*
Y124340D03*
Y119340D03*
Y234340D03*
Y229340D03*
Y224340D03*
Y219340D03*
Y214340D03*
Y209340D03*
Y204340D03*
Y199340D03*
Y194340D03*
Y189340D03*
Y184340D03*
Y179340D03*
X771083Y211784D03*
X821272Y299340D03*
Y294340D03*
Y289340D03*
Y284340D03*
Y279340D03*
Y274340D03*
Y269340D03*
Y264340D03*
Y259340D03*
Y254340D03*
Y249340D03*
Y244340D03*
Y239340D03*
X773000Y315800D03*
X821272Y359340D03*
Y354340D03*
Y349340D03*
Y344340D03*
Y339340D03*
Y334340D03*
Y329340D03*
Y324340D03*
Y319340D03*
Y314340D03*
Y309340D03*
Y304340D03*
Y424340D03*
Y419340D03*
Y414340D03*
Y409340D03*
Y404340D03*
Y399340D03*
Y394340D03*
Y389340D03*
Y384340D03*
Y379340D03*
Y374340D03*
Y369340D03*
Y364340D03*
Y484340D03*
Y479340D03*
Y474340D03*
Y469340D03*
Y464340D03*
Y459340D03*
Y454340D03*
Y449340D03*
Y444340D03*
Y439340D03*
Y434340D03*
Y429340D03*
Y504340D03*
Y509340D03*
Y514340D03*
Y519340D03*
Y524340D03*
Y529340D03*
Y549340D03*
Y544340D03*
Y539340D03*
Y534340D03*
Y499340D03*
Y494340D03*
Y489340D03*
X762550Y565366D03*
X767550D03*
X772550D03*
X777550D03*
X782550D03*
X787550D03*
X792550D03*
X797550D03*
X802550D03*
X807550D03*
X812550D03*
X817550D03*
X821272Y559340D03*
Y554340D03*
G54D104*
G01X48950Y337600D02*
Y340098D01*
X49465Y340613D01*
Y344007D01*
G01X27950Y337800D02*
Y340459D01*
X28465Y340974D01*
Y344207D01*
G01X70650Y338000D02*
Y340695D01*
X71165Y341210D01*
Y344407D01*
G01X52025Y344007D02*
Y338025D01*
X52450Y337600D01*
G01X31025Y344207D02*
Y338225D01*
X31450Y337800D01*
G01X73725Y344407D02*
Y338425D01*
X74150Y338000D01*
G01X70757Y392835D02*
X65375D01*
G01X91745Y337793D02*
Y340399D01*
X92260Y340914D01*
Y344200D01*
G01X94820D02*
Y338218D01*
X95245Y337793D01*
G01X248169Y74454D02*
Y81399D01*
G01X217950Y317000D02*
Y316310D01*
X216640Y315000D01*
Y311500D01*
G01X235350Y316900D02*
Y315429D01*
X234872Y314951D01*
Y311505D01*
G01X253725Y316967D02*
Y315301D01*
X253215Y314791D01*
Y311467D01*
G01X231850Y316900D02*
X232312Y316438D01*
Y311505D01*
G01X250225Y316967D02*
X250655Y316537D01*
Y311467D01*
G01X214450Y317000D02*
X214080Y316630D01*
Y311500D01*
G01X273115Y317151D02*
Y315623D01*
X272637Y315145D01*
Y311756D01*
G01X269615Y317151D02*
X270077Y316689D01*
Y311756D01*
G01X454725Y281497D02*
Y281496D01*
X456693Y279528D01*
G01X454725Y281497D02*
X452757Y279529D01*
G01D02*
Y279528D01*
X454725Y277560D01*
G01X665354Y165354D02*
X665352D01*
X663778Y166928D01*
G01X674803Y165354D02*
Y165355D01*
X673229Y166929D01*
G01X674803Y171653D02*
Y171654D01*
X673229Y173228D01*
G01X677952Y143307D02*
X677953D01*
X679526Y144880D01*
G01X677952Y137008D02*
X676379Y135435D01*
G01X696850Y137008D02*
Y137007D01*
X695274Y135431D01*
G01X696850Y127559D02*
X698425Y129134D01*
G01X665354Y152756D02*
X665352D01*
X663778Y154330D01*
G01X662204Y133858D02*
X662960Y134614D01*
X662961D01*
X663778Y135431D01*
G01X665354Y133858D02*
X665351D01*
X663778Y135431D01*
G01X690551Y133858D02*
X692124Y135431D01*
G01X649606Y149606D02*
Y146456D01*
G01X655905Y174803D02*
X655904D01*
X654330Y176377D01*
G01X652756Y171653D02*
Y171652D01*
G01X655905Y168504D02*
X655904D01*
X654330Y170078D01*
G01X696850Y149606D02*
X695275Y148031D01*
G01X693700Y146456D02*
X695275Y148031D01*
G01X696850Y155905D02*
X695275Y154330D01*
G01X693700Y152756D02*
X693701D01*
X695275Y154330D01*
G01X696850Y174803D02*
X695275Y173228D01*
G01X693700Y171653D02*
X695275Y173228D01*
G01X690551Y174803D02*
X688976Y173228D01*
G01X687401Y171653D02*
X688976Y173228D01*
G01X687401Y174803D02*
X688976Y173228D01*
G01X684252Y174803D02*
X682677Y173228D01*
G01X681102Y171653D02*
X682677Y173228D01*
G01X671653Y165354D02*
X671652D01*
X670078Y166928D01*
G01X684252Y168504D02*
X682677Y166929D01*
G01X681102Y165354D02*
X682677Y166929D01*
G01X690551Y168504D02*
X688976Y166929D01*
G01X687401Y165354D02*
X688976Y166929D01*
G01X696850Y168504D02*
X695275Y166929D01*
G01X693700Y165354D02*
X695275Y166929D01*
G01X662204Y174803D02*
Y174801D01*
X663778Y173227D01*
G01X662204Y168504D02*
X663778Y170078D01*
G01X665354Y168504D02*
X665352D01*
X663778Y170078D01*
G01X665354Y174803D02*
X665352D01*
X663778Y176377D01*
G01X665354Y171653D02*
X665352D01*
X663778Y173227D01*
G01X696850Y162204D02*
X695275Y160629D01*
G01X693700Y159055D02*
X693701D01*
X695275Y160629D01*
G01X690551Y162204D02*
X688976Y160629D01*
G01X687401Y159055D02*
X687402D01*
X688976Y160629D01*
G01X684252Y162204D02*
X684251D01*
X682677Y160630D01*
G01X681102Y159055D02*
X682677Y160630D01*
G01X690551Y155905D02*
X688976Y154330D01*
G01X687401Y152756D02*
X687402D01*
X688976Y154330D01*
G01X684252Y155905D02*
X682677Y154330D01*
G01X681102Y152756D02*
X681103D01*
X682677Y154330D01*
G01X677952Y162204D02*
X679527Y163779D01*
G01X684252Y149606D02*
X682677Y148031D01*
G01X681102Y146456D02*
X682677Y148031D01*
G01X690551Y149606D02*
X688976Y148031D01*
G01X687401Y146456D02*
X688976Y148031D01*
G01X671653Y133858D02*
Y133820D01*
X670116Y132283D01*
G01X693700Y130708D02*
Y130671D01*
X692148Y129119D01*
G01X690551Y130708D02*
X690559D01*
X692148Y129119D01*
G01X646456Y152756D02*
X646494D01*
X648059Y151191D01*
G01X649606Y152756D02*
X651181Y151181D01*
G01X649606Y149606D02*
Y149644D01*
X648059Y151191D01*
G01X659055Y130708D02*
X659054D01*
X657480Y129134D01*
G01X659055Y127559D02*
X657480Y129134D01*
G01X687401Y127559D02*
X685827Y125985D01*
G01X693700Y174803D02*
X695275Y173228D01*
G01X696850Y143307D02*
X696849D01*
X693700Y146456D01*
G01X690551Y143307D02*
X690550D01*
X687401Y146456D01*
G01X668504Y133858D02*
X668541D01*
X670116Y132283D01*
G01X671653Y130708D02*
Y130746D01*
X670116Y132283D01*
G01X662204Y127559D02*
X659055D01*
G01X668504Y174803D02*
Y174801D01*
X670078Y173227D01*
G01X668504Y171653D02*
X670078Y173227D01*
G01X671653Y174803D02*
Y174802D01*
X670078Y173227D01*
G01X665354Y140157D02*
Y140155D01*
X666928Y138581D01*
G01X665354Y137008D02*
X665355D01*
X666928Y138581D01*
G01X668504Y137008D02*
X668501D01*
X666928Y138581D01*
G01X668504Y140157D02*
X666928Y138581D01*
G01X671653Y140157D02*
Y140155D01*
X673227Y138581D01*
G01X671653Y137008D02*
X671654D01*
X673227Y138581D01*
G01X674803Y140157D02*
X673227Y138581D01*
G01X674803Y137008D02*
X674800D01*
X673227Y138581D01*
G01X677952Y140157D02*
Y140155D01*
X679526Y138581D01*
G01X681102Y140157D02*
X679526Y138581D01*
G01X684252Y140157D02*
Y140154D01*
X685825Y138581D01*
G01X687401Y140157D02*
X685825Y138581D01*
G01X671653Y143307D02*
X671654D01*
X673227Y144880D01*
G01X674803Y143307D02*
X674800D01*
X673227Y144880D01*
G01X665354Y146456D02*
Y146454D01*
X666928Y144880D01*
G01D02*
X665355Y143307D01*
X665354D01*
G01X668504D02*
X668501D01*
X666928Y144880D01*
G01X690551Y140157D02*
Y140156D01*
X692125Y138582D01*
G01X690551Y137008D02*
X692125Y138582D01*
G01X696850Y140157D02*
X698425Y138582D01*
G01X693700Y133858D02*
X693697D01*
X692124Y135431D01*
G01X662204Y152756D02*
X663778Y154330D01*
G01X696850Y130708D02*
X696851D01*
X698425Y129134D01*
G01X684252Y143307D02*
X684251D01*
X681102Y146456D01*
G01X687401Y143307D02*
X690551Y140157D01*
G01X684252Y137008D02*
X685825Y138581D01*
G01X693700Y137008D02*
Y137007D01*
X692124Y135431D01*
G01X693700Y140157D02*
X692125Y138582D01*
G01X696850Y133858D02*
X696847D01*
X695274Y135431D01*
G01X677952Y133858D02*
Y133862D01*
X676379Y135435D01*
G01X684252Y133858D02*
Y133862D01*
X682679Y135435D01*
G01X687401Y133858D02*
X688978Y135435D01*
G01X687401Y137008D02*
X687405D01*
X688978Y135435D01*
G01X681102Y137008D02*
X681106D01*
X682679Y135435D01*
G01X681102Y133858D02*
X682679Y135435D01*
G01X677952Y130708D02*
X681102Y133858D01*
G01X684252Y130708D02*
Y130709D01*
X687401Y133858D01*
G01X696850Y177952D02*
X696849D01*
X693700Y174803D01*
G01X659055Y140157D02*
Y140158D01*
X660629Y141732D01*
G01X681102Y143307D02*
X681099D01*
X679526Y144880D01*
G01X668504Y177952D02*
X668503D01*
X665354Y174803D01*
G01X671653Y168504D02*
Y168503D01*
X670078Y166928D01*
G01X677952Y149606D02*
X681102Y152756D01*
G01X677952Y146456D02*
Y146454D01*
X679526Y144880D01*
G01X674803Y146456D02*
X673227Y144880D01*
G01X668504Y146456D02*
X668506D01*
X670080Y148030D01*
G01X671653Y146456D02*
Y146457D01*
X670080Y148030D01*
G01X671653Y149606D02*
Y149603D01*
X670080Y148030D01*
G01X671653Y149606D02*
X674803Y152756D01*
G01Y174803D02*
Y174802D01*
X673229Y173228D01*
G01X677952Y171653D02*
Y171654D01*
X674803Y174803D01*
G01X677952D02*
X674803Y177952D01*
G01X677952Y155905D02*
X681102Y159055D01*
G01X671653Y155905D02*
X670078Y154330D01*
G01D02*
X668504Y152756D01*
G01D02*
X665354Y149606D01*
G01D02*
X662204Y146456D01*
G01X673227Y157479D02*
X671653Y155905D01*
G01X674803D02*
X674801D01*
X673227Y157479D01*
G01X674803Y159055D02*
X673227Y157479D01*
G01X668504Y165354D02*
X670078Y166928D01*
G01X671653Y159055D02*
Y159053D01*
X673227Y157479D01*
G01X668504Y162204D02*
X665354Y165354D01*
G01X677952Y168504D02*
X677953D01*
X681102Y171653D01*
G01X671653Y162204D02*
Y162205D01*
X668504Y165354D01*
G01X674803Y162204D02*
X677952D01*
G01X662204Y165354D02*
X663778Y166928D01*
G01X662204Y162204D02*
Y162203D01*
X663778Y160629D01*
G01X662204Y155905D02*
Y155904D01*
X663778Y154330D01*
G01X665354Y162204D02*
X665353D01*
X663778Y160629D01*
G01X668504Y159055D02*
X668503D01*
X665354Y162204D01*
G01X652756Y171652D02*
X654330Y170078D01*
G01X649606Y174803D02*
Y174802D01*
X652756Y171652D01*
G01X665354Y159055D02*
X665352D01*
X663778Y160629D01*
G01X662204Y159055D02*
X663778Y160629D01*
G01X665354Y155905D02*
X665353D01*
X663778Y154330D01*
G01X659055Y152756D02*
X659017D01*
X657480Y151219D01*
G01X655905Y152756D02*
X655943D01*
X657480Y151219D01*
G01X659055Y149606D02*
Y149644D01*
X657480Y151219D01*
G01X674803Y168504D02*
Y168505D01*
X673229Y170079D01*
G01X677952Y177952D02*
X677953D01*
X681102Y174803D01*
G01X677952Y159055D02*
X677953D01*
X679527Y160629D01*
G01X681102Y162204D02*
X679527Y160629D01*
G01X677952Y152756D02*
X677953D01*
X679527Y154330D01*
G01X681102Y155905D02*
X679527Y154330D01*
G01X681102Y130708D02*
X682675Y132281D01*
G01X687401Y130708D02*
X688974Y132281D01*
G01X674803Y133858D02*
Y133854D01*
X676376Y132281D01*
G01X674803Y130708D02*
X676376Y132281D01*
G01X637952Y142515D02*
X638744Y143307D01*
X643307D01*
G01X659055Y133858D02*
X657481Y132284D01*
G01X652756Y190551D02*
X651181Y188976D01*
G01X679527Y182679D02*
X677953Y181105D01*
X677952D01*
Y181102D01*
G01Y187401D02*
X677953D01*
X679527Y188975D01*
G01X674803Y184252D02*
X674805D01*
X676379Y182678D01*
G01X693700Y187401D02*
X692126Y185827D01*
G01X677952Y193700D02*
Y193699D01*
X676379Y192126D01*
G01X652756Y177952D02*
Y177951D01*
X654330Y176377D01*
G01X652756Y184252D02*
Y184250D01*
X654330Y182676D01*
G01X662204Y193700D02*
X660629Y192125D01*
G01D02*
X659055Y190551D01*
G01X668504Y193700D02*
X666929Y192125D01*
G01X687401Y193700D02*
X688976Y192125D01*
G01X665354Y190551D02*
X665355D01*
X666929Y192125D01*
G01X690551Y190551D02*
X690550D01*
X688976Y192125D01*
G01X696850Y190551D02*
X696851D01*
X698425Y192125D01*
G01X655905Y181102D02*
X655904D01*
X654330Y182676D01*
G01X659055Y200000D02*
X660630Y198425D01*
G01X674803Y203149D02*
X676377Y204723D01*
G01X674803Y200000D02*
X676377Y201574D01*
G01X674803Y196850D02*
X676377Y198424D01*
G01X687401Y203149D02*
X685826Y201574D01*
G01X684252Y200000D02*
X685826Y201574D01*
G01X687401Y200000D02*
Y199999D01*
X685826Y198424D01*
G01X684252Y196850D02*
X685826Y198424D01*
G01X687401Y196850D02*
X687400D01*
X685826Y198424D01*
G01X684252Y193700D02*
X682677Y192125D01*
G01X684252Y190551D02*
X684251D01*
X682677Y192125D01*
G01X681102Y193700D02*
X682677Y192125D01*
G01X681102Y190551D02*
X681103D01*
X682677Y192125D01*
G01X681102Y190551D02*
Y190549D01*
X682676Y188975D01*
G01X684252Y187401D02*
X684250D01*
X682676Y188975D01*
G01X684252Y184252D02*
X684250D01*
X682676Y185826D01*
G01X681102Y184252D02*
X682676Y185826D01*
G01X684252Y181102D02*
X682677Y182677D01*
G01X681102Y181102D02*
X682677Y182677D01*
G01X684252Y177952D02*
X684250D01*
X682676Y179526D01*
G01X681102Y177952D02*
X682676Y179526D01*
G01X662204Y184252D02*
Y184250D01*
X663778Y182676D01*
G01X662204Y181102D02*
Y181100D01*
X663778Y179526D01*
G01X662204Y177952D02*
Y177951D01*
X663778Y176377D01*
G01X665354Y181102D02*
X665352D01*
X663778Y182676D01*
G01X665354Y177952D02*
X665352D01*
X663778Y179526D01*
G01X665354Y184252D02*
X663778Y182676D01*
G01X668504Y184252D02*
X668506D01*
X670080Y182678D01*
G01X671653Y184252D02*
Y184251D01*
X670080Y182678D01*
G01X668504Y181102D02*
X670080Y182678D01*
G01X671653Y181102D02*
Y181105D01*
X670080Y182678D01*
G01X674803Y193700D02*
X674805D01*
G01X674803Y190551D02*
X674804D01*
X676379Y192126D01*
G01X681102Y187401D02*
X682676Y188975D01*
G01X693700Y177952D02*
Y177953D01*
X692126Y179527D01*
G01X690551Y187401D02*
X690552D01*
X692126Y185827D01*
G01X693700Y181102D02*
Y181101D01*
X692126Y179527D01*
G01X690551Y181102D02*
X690552D01*
X692126Y182676D01*
G01X693700Y184252D02*
Y184250D01*
X692126Y182676D01*
G01X690551Y184252D02*
Y184251D01*
X692126Y182676D01*
G01X687401Y177952D02*
Y177953D01*
X684252Y181102D01*
G01X687401D02*
Y181103D01*
X684252Y184252D01*
G01X687401D02*
X684252Y187401D01*
G01X687401D02*
Y187402D01*
X684252Y190551D01*
G01X696850Y187401D02*
X696849D01*
X693700Y184252D01*
G01X696850D02*
X693700Y181102D01*
G01X696850D02*
X693700Y177952D01*
G01X674803Y181102D02*
X676379Y182678D01*
G01X677952Y184252D02*
X677954D01*
X679527Y182679D01*
G01X677952Y190551D02*
Y190550D01*
G01D02*
X679527Y188975D01*
G01X674803Y187401D02*
X677952Y190550D01*
G01X674805Y193700D02*
X676379Y192126D01*
G01X671653Y190551D02*
X671656D01*
X674805Y193700D01*
G01X671653Y177952D02*
X674803Y181102D01*
G01Y177952D02*
Y177953D01*
X677952Y181102D01*
G01X646594Y210875D02*
X652756Y204713D01*
Y203149D01*
G01X646456Y200000D02*
Y199999D01*
X643307Y196850D01*
G01D02*
X640584Y194127D01*
G01X649606Y190551D02*
X651181Y188976D01*
G01X655905Y187401D02*
X659055Y190551D01*
G01X655905Y193700D02*
X652756Y190551D01*
G01X655905Y196850D02*
Y193700D01*
G01X683913Y213313D02*
X684252Y212974D01*
Y203149D01*
G01X652756Y193700D02*
X651181Y192125D01*
G01X665354Y193700D02*
X663779Y192125D01*
G01D02*
X662205Y190551D01*
X662204D01*
G01X659055Y193700D02*
X657480Y192125D01*
G01D02*
X655906Y190551D01*
X655905D01*
G01X668504D02*
X670078Y192125D01*
G01D02*
X671653Y193700D01*
G01X655905Y184252D02*
X655904D01*
X654330Y185826D01*
G01D02*
X652756Y187400D01*
Y187401D01*
G01X655905Y177952D02*
X655904D01*
X654330Y179526D01*
G01D02*
X652756Y181100D01*
Y181102D01*
G01X685826Y192125D02*
X687400Y190551D01*
X687401D01*
G01X693700D02*
X693699D01*
X692125Y192125D01*
G01D02*
X690551Y193699D01*
Y193700D01*
G01X676361Y373173D02*
X679473D01*
X679905Y372741D01*
X681419D01*
X682000Y372160D01*
G01X670494Y431956D02*
X667414D01*
G01X675614Y425456D02*
X681536D01*
X681540Y425460D01*
G01X706299Y137008D02*
X704725Y135434D01*
G01X706299Y140157D02*
X707874Y141732D01*
G01X703149Y140157D02*
X701574Y138582D01*
G01X706299Y130708D02*
X704724Y132283D01*
G01X725196Y168504D02*
X726770Y166930D01*
G01X725196Y174803D02*
X726770Y173229D01*
G01X715748Y140157D02*
X717322Y141731D01*
G01X718897Y174803D02*
X720472Y173228D01*
G01X722047Y171653D02*
X720472Y173228D01*
G01X718897Y171653D02*
X720472Y173228D01*
G01X718897Y168504D02*
Y168502D01*
X720471Y166928D01*
G01X722047Y168504D02*
X720471Y166928D01*
G01X715748Y168504D02*
Y168502D01*
X717322Y166928D01*
G01X718897Y165354D02*
X718896D01*
X717322Y166928D01*
G01X715748Y165354D02*
Y165352D01*
X717322Y163778D01*
G01X718897Y162204D02*
X718896D01*
X717322Y163778D01*
G01X722047Y159055D02*
X722046D01*
X720472Y160629D01*
G01X718897Y159055D02*
X718898D01*
X720472Y160629D01*
G01X725196Y155905D02*
Y155906D01*
X722047Y159055D01*
G01X715748Y162204D02*
X715746D01*
X714172Y163778D01*
G01X712598Y165354D02*
Y165352D01*
X714172Y163778D01*
G01X712598Y162204D02*
X714172Y163778D01*
G01X715748Y159055D02*
Y159053D01*
X717322Y157479D01*
G01X718897Y155905D02*
X718896D01*
X717322Y157479D01*
G01X718897Y155905D02*
X720472Y154330D01*
G01X722047Y152756D02*
X722046D01*
X720472Y154330D01*
G01X718897Y152756D02*
X718898D01*
X720472Y154330D01*
G01X715748Y152756D02*
Y152754D01*
X717322Y151180D01*
G01X718897Y149606D02*
X718896D01*
X717322Y151180D01*
G01X718897Y149606D02*
X720472Y148031D01*
G01X722047Y146456D02*
X720472Y148031D01*
G01X725196Y149606D02*
Y149607D01*
X722047Y152756D01*
G01X725196Y143307D02*
X722047Y146456D01*
G01X718897D02*
X720472Y148031D01*
G01X715748Y146456D02*
Y146454D01*
X717322Y144880D01*
G01X718897Y143307D02*
X718895D01*
X717322Y144880D01*
G01X722047Y140157D02*
X720472Y141732D01*
G01X725196Y137008D02*
X722047Y140157D01*
G01X718897D02*
X718896D01*
X717322Y141731D01*
G01X718897Y137008D02*
X720472Y135433D01*
G01X722047Y133858D02*
X720472Y135433D01*
G01X718897Y133858D02*
X720472Y135433D01*
G01X725196Y130708D02*
Y130709D01*
X722047Y133858D01*
G01X715748Y143307D02*
X715745D01*
X714172Y144880D01*
G01X712598Y146456D02*
Y146454D01*
X714172Y144880D01*
G01X712598Y143307D02*
X712599D01*
X714172Y144880D01*
G01X715748Y155905D02*
X715746D01*
X714172Y157479D01*
G01X712598Y159055D02*
Y159053D01*
X714172Y157479D01*
G01X712598Y155905D02*
X714172Y157479D01*
G01X709448Y162204D02*
X707873Y160629D01*
G01X709448Y159055D02*
X709447D01*
X707873Y160629D01*
G01X706299Y159055D02*
X707873Y160629D01*
G01X709448Y155905D02*
X707873Y154330D01*
G01X709448Y152756D02*
X709447D01*
X707873Y154330D01*
G01X706299Y152756D02*
X707873Y154330D01*
G01X712598Y152756D02*
Y152754D01*
X714172Y151180D01*
G01X715748Y149606D02*
X715746D01*
X714172Y151180D01*
G01X712598Y149606D02*
X714172Y151180D01*
G01X709448Y149606D02*
X707873Y148031D01*
G01X706299Y146456D02*
Y146457D01*
X707873Y148031D01*
G01X709448Y146456D02*
X707873Y148031D01*
G01X709448Y143307D02*
X711023Y141732D01*
G01X709448Y140157D02*
X711023Y141732D01*
G01X703149Y149606D02*
X701574Y148031D01*
G01X700000Y146456D02*
Y146457D01*
X701574Y148031D01*
G01X703149Y155905D02*
X701574Y154330D01*
G01X700000Y152756D02*
X701574Y154330D01*
G01X715748Y174803D02*
X714172Y173227D01*
G01X715748Y171653D02*
X715746D01*
X714172Y173227D01*
G01X712598Y171653D02*
X714172Y173227D01*
G01X709448Y174803D02*
X707873Y173228D01*
G01X706299Y171653D02*
Y171654D01*
X707873Y173228D01*
G01X709448Y168504D02*
X707873Y166929D01*
G01X706299Y165354D02*
Y165355D01*
X707873Y166929D01*
G01X709448Y165354D02*
X707873Y166929D01*
G01X712598Y168504D02*
Y165354D01*
G01Y168504D02*
X715748D01*
G01X712598Y174803D02*
Y174801D01*
X714172Y173227D01*
G01X703149Y174803D02*
X701574Y173228D01*
G01X700000Y171653D02*
Y171654D01*
X701574Y173228D01*
G01X700000Y174803D02*
Y174802D01*
X701574Y173228D01*
G01X703149Y168504D02*
X701574Y166929D01*
G01X700000Y165354D02*
Y165355D01*
X701574Y166929D01*
G01X703149Y162204D02*
X701574Y160629D01*
G01X700000Y159055D02*
X701574Y160629D01*
G01X722047Y127559D02*
Y127558D01*
X725196Y124409D01*
G01X715748Y162204D02*
X717322Y163778D01*
G01X722047Y165354D02*
X722045D01*
X720471Y166928D01*
G01X703149Y143307D02*
X700000Y146456D01*
G01Y133858D02*
X698425Y135433D01*
G01X728346Y168504D02*
X728344D01*
X726770Y166930D01*
G01X700000Y130708D02*
X699999D01*
X698425Y129134D01*
G01X700000Y137008D02*
X698425Y135433D01*
G01X700000Y140157D02*
X698425Y138582D01*
G01X703149Y130708D02*
X704724Y132283D01*
G01X709448Y130708D02*
X711023Y132283D01*
G01X712598Y130708D02*
X711023Y132283D01*
G01X718897Y127559D02*
X718896D01*
X717322Y129133D01*
G01X718897Y130708D02*
X717322Y129133D01*
G01X715748Y127559D02*
X717322Y129133D01*
G01X701574Y138582D02*
X703149Y137007D01*
X703150Y137008D01*
X703149D01*
G01X706299Y133858D02*
Y133860D01*
X704725Y135434D01*
G01X712598Y137008D02*
X712597D01*
X709448Y140157D01*
G01Y137008D02*
X706299Y140157D01*
G01X715748Y137008D02*
X718897Y140157D01*
G01X715748Y133858D02*
Y133857D01*
X718897Y130708D01*
G01X715748D02*
X712598Y133858D01*
G01X715748Y130708D02*
Y130707D01*
X717322Y129133D01*
G01X703149Y133858D02*
Y133859D01*
X701575Y135433D01*
G01X709448Y133858D02*
Y133859D01*
X706299Y137008D01*
G01X711023Y132283D02*
X712598Y133858D01*
G01X728346Y171653D02*
X726770Y173229D01*
G01X731496Y168504D02*
X731495D01*
G01D02*
X733069Y166930D01*
G01X731495Y168504D02*
X728346D01*
G01X734645D02*
X734643D01*
X733069Y166930D01*
G01X725196Y146456D02*
X723621Y148031D01*
G01X725196Y165354D02*
X723621Y166929D01*
G01X725196Y171653D02*
X723621Y173228D01*
G01X725196Y133858D02*
X723621Y135433D01*
G01X725196Y140157D02*
X723621Y141732D01*
G01X725196Y127559D02*
X725195D01*
X723621Y129133D01*
G01X725196Y159055D02*
X725195D01*
X723621Y160629D01*
G01X725196Y152756D02*
X725195D01*
X723621Y154330D01*
G01Y141732D02*
X722047Y143306D01*
Y143307D01*
G01X723621Y129133D02*
X722047Y130707D01*
Y130708D01*
G01X723621Y135433D02*
X722047Y137007D01*
Y137008D01*
G01X723621Y173228D02*
X722047Y174802D01*
Y174803D01*
G01X723621Y160629D02*
X722047Y162203D01*
Y162204D01*
G01X723621Y154330D02*
X722047Y155904D01*
Y155905D01*
G01X723621Y148031D02*
X722047Y149605D01*
Y149606D01*
G01X725196Y181102D02*
X726770Y179528D01*
G01X725196Y187401D02*
X726770Y185827D01*
G01X718897Y193700D02*
X720472Y192125D01*
G01X700000Y193700D02*
X698425Y192125D01*
G01X706299Y193700D02*
X704724Y192125D01*
G01X712598Y193700D02*
Y193699D01*
X711024Y192125D01*
G01X703149Y190551D02*
X703150D01*
X704724Y192125D01*
G01X709448Y190551D02*
X709450D01*
X711024Y192125D01*
G01X722047Y190551D02*
X722046D01*
X720472Y192125D01*
G01X725196Y193700D02*
X726770Y192126D01*
G01X722047Y184252D02*
X722014D01*
X720437Y185829D01*
G01X718897Y187401D02*
Y187369D01*
X720437Y185829D01*
G01X718897Y184252D02*
Y184289D01*
X720437Y185829D01*
G01X722047Y177952D02*
X720472Y179527D01*
G01X718897Y181102D02*
X720472Y179527D01*
G01X718897Y177952D02*
X720472Y179527D01*
G01X715748Y177952D02*
X715746D01*
X714172Y179526D01*
G01X712598Y177952D02*
X714172Y179526D01*
G01X709448Y177952D02*
X711022Y179526D01*
G01X709448Y181102D02*
Y181100D01*
X711022Y179526D01*
G01X712598Y181102D02*
X712596D01*
X711022Y182676D01*
G01X709448Y184252D02*
Y184250D01*
X711022Y182676D01*
G01X703149Y177952D02*
Y177953D01*
X701575Y179527D01*
G01X700000Y187401D02*
X700001D01*
X701575Y185827D01*
G01X703149Y187401D02*
X701575Y185827D01*
G01X711022Y185825D02*
X712596Y184251D01*
X712598D01*
Y184252D01*
G01X709448Y187401D02*
Y187399D01*
X711022Y185825D01*
G01X703149Y181102D02*
Y181101D01*
X701575Y179527D01*
G01X712598Y187401D02*
Y187402D01*
X711024Y188976D01*
G01X715748Y181102D02*
X717322Y182676D01*
G01X715748Y184252D02*
X717322Y182678D01*
Y182676D01*
G01X700000Y184252D02*
Y184251D01*
X701575Y182676D01*
G01X703149Y184252D02*
Y184250D01*
X701575Y182676D01*
G01X700000Y181102D02*
X700001D01*
X701575Y182676D01*
G01X706299Y187401D02*
X703149Y190551D01*
G01X706299Y184252D02*
X706298D01*
X703149Y187401D01*
G01X706299Y181102D02*
X703149Y184252D01*
G01X706299Y177952D02*
X703149Y181102D01*
G01X701574Y192125D02*
X703149Y193700D01*
G01X700000Y190551D02*
X701574Y192125D01*
G01X706299Y190551D02*
X707873Y192125D01*
G01X725196Y177952D02*
X723621Y179527D01*
G01X718897Y190551D02*
X715748Y193700D01*
G01X725196Y184252D02*
X725195D01*
X723621Y185826D01*
G01X725196Y190551D02*
X725195D01*
X723621Y192125D01*
G01X715748Y193700D02*
X714173Y192125D01*
G01X723621Y179527D02*
X722047Y181101D01*
Y181102D01*
G01X723621Y185826D02*
X722047Y187400D01*
Y187401D01*
G01X723621Y192125D02*
X722047Y193699D01*
Y193700D01*
G01X714173Y192125D02*
X712599Y190551D01*
X712598D01*
G01X707873Y192125D02*
X709448Y193700D01*
X696850Y111811D03*
X693700D03*
X690551D03*
X687401D03*
X684252D03*
X681102D03*
X677952D03*
X674803D03*
X671653D03*
X668504D03*
X665354D03*
X662204D03*
X659055D03*
X655905D03*
X652756D03*
X696850Y114960D03*
X693700D03*
X690551D03*
X687401D03*
X684252D03*
X681102D03*
X677952D03*
X674803D03*
X671653D03*
X668504D03*
X665354D03*
X662204D03*
X659055D03*
X655905D03*
X652756D03*
X696850Y118110D03*
X693700D03*
X690551D03*
X687401D03*
X684252D03*
X681102D03*
X677952D03*
X674803D03*
X671653D03*
X668504D03*
X665354D03*
X662204D03*
X659055D03*
X655905D03*
X652756D03*
X696850Y121260D03*
X693700D03*
X690551D03*
X687401D03*
X684252D03*
X681102D03*
X677952D03*
X674803D03*
X671653D03*
X668504D03*
X665354D03*
X662204D03*
X659055D03*
X655905D03*
X652756D03*
X649606D03*
X646456D03*
X643307D03*
X696850Y124409D03*
X693700D03*
X690551D03*
X687401D03*
X684252D03*
X681102D03*
X677952D03*
X674803D03*
X671653D03*
X668504D03*
X665354D03*
X662204D03*
X659055D03*
X655905D03*
X652756D03*
X649606D03*
X646456D03*
X643307D03*
X696850Y127559D03*
X693700D03*
X690551D03*
X687401D03*
X684252D03*
X681102D03*
X677952D03*
X674803D03*
X671653D03*
X668504D03*
X665354D03*
X662204D03*
X659055D03*
X655905D03*
X652756D03*
X649606D03*
X646456D03*
X643307D03*
X696850Y130708D03*
X693700D03*
X690551D03*
X687401D03*
X684252D03*
X681102D03*
X677952D03*
X674803D03*
X671653D03*
X668504D03*
X665354D03*
X662204D03*
X659055D03*
X655905D03*
X652756D03*
X649606D03*
X646456D03*
X643307D03*
X696850Y133858D03*
X693700D03*
X690551D03*
X687401D03*
X684252D03*
X681102D03*
X677952D03*
X674803D03*
X671653D03*
X668504D03*
X665354D03*
X662204D03*
X659055D03*
X655905D03*
X652756D03*
X649606D03*
X646456D03*
X643307D03*
X696850Y137008D03*
X693700D03*
X690551D03*
X687401D03*
X684252D03*
X681102D03*
X677952D03*
X674803D03*
X671653D03*
X668504D03*
X665354D03*
X662204D03*
X659055D03*
X655905D03*
X652756D03*
X649606D03*
X646456D03*
X643307D03*
X696850Y140157D03*
X693700D03*
X690551D03*
X687401D03*
X684252D03*
X681102D03*
X677952D03*
X674803D03*
X671653D03*
X668504D03*
X665354D03*
X662204D03*
X659055D03*
X655905D03*
X652756D03*
X649606D03*
X646456D03*
X643307D03*
X696850Y143307D03*
X693700D03*
X690551D03*
X687401D03*
X684252D03*
X681102D03*
X677952D03*
X674803D03*
X671653D03*
X668504D03*
X665354D03*
X662204D03*
X659055D03*
X655905D03*
X652756D03*
X649606D03*
X646456D03*
X643307D03*
X696850Y146456D03*
X693700D03*
X690551D03*
X687401D03*
X684252D03*
X681102D03*
X677952D03*
X674803D03*
X671653D03*
X668504D03*
X665354D03*
X662204D03*
X659055D03*
X655905D03*
X652756D03*
X649606D03*
X646456D03*
X643307D03*
X696850Y149606D03*
X693700D03*
X690551D03*
X687401D03*
X684252D03*
X681102D03*
X677952D03*
X674803D03*
X671653D03*
X668504D03*
X665354D03*
X662204D03*
X659055D03*
X655905D03*
X652756D03*
X649606D03*
X646456D03*
X643307D03*
X696850Y152756D03*
X693700D03*
X690551D03*
X687401D03*
X684252D03*
X681102D03*
X677952D03*
X674803D03*
X671653D03*
X668504D03*
X665354D03*
X662204D03*
X659055D03*
X655905D03*
X652756D03*
X649606D03*
X646456D03*
X643307D03*
X696850Y155905D03*
X693700D03*
X690551D03*
X687401D03*
X684252D03*
X681102D03*
X677952D03*
X674803D03*
X671653D03*
X668504D03*
X665354D03*
X662204D03*
X659055D03*
X655905D03*
X652756D03*
X649606D03*
X646456D03*
X643307D03*
X696850Y159055D03*
X693700D03*
X690551D03*
X687401D03*
X684252D03*
X681102D03*
X677952D03*
X674803D03*
X671653D03*
X668504D03*
X665354D03*
X662204D03*
X659055D03*
X655905D03*
X652756D03*
X649606D03*
X646456D03*
X643307D03*
X696850Y162204D03*
X693700D03*
X690551D03*
X687401D03*
X684252D03*
X681102D03*
X677952D03*
X674803D03*
X671653D03*
X668504D03*
X665354D03*
X662204D03*
X659055D03*
X655905D03*
X652756D03*
X649606D03*
X646456D03*
X643307D03*
X696850Y165354D03*
X693700D03*
X690551D03*
X687401D03*
X684252D03*
X681102D03*
X677952D03*
X674803D03*
X671653D03*
X668504D03*
X665354D03*
X662204D03*
X659055D03*
X655905D03*
X652756D03*
X649606D03*
X646456D03*
X643307D03*
X696850Y168504D03*
X693700D03*
X690551D03*
X687401D03*
X684252D03*
X681102D03*
X677952D03*
X674803D03*
X671653D03*
X668504D03*
X665354D03*
X662204D03*
X659055D03*
X655905D03*
X652756D03*
X649606D03*
X646456D03*
X643307D03*
X696850Y171653D03*
X693700D03*
X690551D03*
X687401D03*
X684252D03*
X681102D03*
X677952D03*
X674803D03*
X671653D03*
X668504D03*
X665354D03*
X662204D03*
X659055D03*
X655905D03*
X652756D03*
X649606D03*
X646456D03*
X643307D03*
X696850Y174803D03*
X693700D03*
X690551D03*
X687401D03*
X684252D03*
X681102D03*
X677952D03*
X674803D03*
X671653D03*
X668504D03*
X665354D03*
X662204D03*
X659055D03*
X655905D03*
X652756D03*
X649606D03*
X646456D03*
X643307D03*
X696850Y177952D03*
X693700D03*
X690551D03*
X687401D03*
X684252D03*
X681102D03*
X677952D03*
X674803D03*
X671653D03*
X668504D03*
X665354D03*
X662204D03*
X659055D03*
X655905D03*
X652756D03*
X649606D03*
X646456D03*
X643307D03*
X696850Y181102D03*
X693700D03*
X690551D03*
X687401D03*
X684252D03*
X681102D03*
X677952D03*
X674803D03*
X671653D03*
X668504D03*
X665354D03*
X662204D03*
X659055D03*
X655905D03*
X652756D03*
X649606D03*
X646456D03*
X643307D03*
X696850Y184252D03*
X693700D03*
X690551D03*
X687401D03*
X684252D03*
X681102D03*
X677952D03*
X674803D03*
X671653D03*
X668504D03*
X665354D03*
X662204D03*
X659055D03*
X655905D03*
X652756D03*
X649606D03*
X646456D03*
X643307D03*
X696850Y187401D03*
X693700D03*
X690551D03*
X687401D03*
X684252D03*
X681102D03*
X677952D03*
X674803D03*
X671653D03*
X668504D03*
X665354D03*
X662204D03*
X659055D03*
X655905D03*
X652756D03*
X649606D03*
X646456D03*
X643307D03*
X696850Y190551D03*
X693700D03*
X690551D03*
X687401D03*
X684252D03*
X681102D03*
X677952D03*
X674803D03*
X671653D03*
X668504D03*
X665354D03*
X662204D03*
X659055D03*
X655905D03*
X652756D03*
X649606D03*
X646456D03*
X643307D03*
X696850Y193700D03*
X693700D03*
X690551D03*
X687401D03*
X684252D03*
X681102D03*
X677952D03*
X674803D03*
X671653D03*
X668504D03*
X665354D03*
X662204D03*
X659055D03*
X655905D03*
X652756D03*
X649606D03*
X646456D03*
X643307D03*
X696850Y196850D03*
X693700D03*
X690551D03*
X687401D03*
X684252D03*
X681102D03*
X677952D03*
X674803D03*
X671653D03*
X668504D03*
X665354D03*
X662204D03*
X659055D03*
X655905D03*
X652756D03*
X696850Y200000D03*
X693700D03*
X690551D03*
X687401D03*
X684252D03*
X681102D03*
X677952D03*
X674803D03*
X671653D03*
X668504D03*
X665354D03*
X662204D03*
X659055D03*
X655905D03*
X652756D03*
X696850Y203149D03*
X693700D03*
X690551D03*
X687401D03*
X684252D03*
X681102D03*
X677952D03*
X674803D03*
X671653D03*
X668504D03*
X665354D03*
X662204D03*
X659055D03*
X655905D03*
X652756D03*
X725196Y111811D03*
X722047D03*
X718897D03*
X715748D03*
X712598D03*
X709448D03*
X706299D03*
X703149D03*
X700000D03*
X725196Y114960D03*
X722047D03*
X718897D03*
X715748D03*
X712598D03*
X709448D03*
X706299D03*
X703149D03*
X700000D03*
X725196Y118110D03*
X722047D03*
X718897D03*
X715748D03*
X712598D03*
X709448D03*
X706299D03*
X703149D03*
X700000D03*
X734645Y121260D03*
X731496D03*
X728346D03*
X725196D03*
X722047D03*
X718897D03*
X715748D03*
X712598D03*
X709448D03*
X706299D03*
X703149D03*
X700000D03*
X734645Y124409D03*
X731496D03*
X728346D03*
X725196D03*
X722047D03*
X718897D03*
X715748D03*
X712598D03*
X709448D03*
X706299D03*
X703149D03*
X700000D03*
X734645Y127559D03*
X731496D03*
X728346D03*
X725196D03*
X722047D03*
X718897D03*
X715748D03*
X712598D03*
X709448D03*
X706299D03*
X703149D03*
X700000D03*
X734645Y130708D03*
X731496D03*
X728346D03*
X725196D03*
X722047D03*
X718897D03*
X715748D03*
X712598D03*
X709448D03*
X706299D03*
X703149D03*
X700000D03*
X734645Y133858D03*
X731496D03*
X728346D03*
X725196D03*
X722047D03*
X718897D03*
X715748D03*
X712598D03*
X709448D03*
X706299D03*
X703149D03*
X700000D03*
X734645Y137008D03*
X731496D03*
X728346D03*
X725196D03*
X722047D03*
X718897D03*
X715748D03*
X712598D03*
X709448D03*
X706299D03*
X703149D03*
X700000D03*
X734645Y140157D03*
X731496D03*
X728346D03*
X725196D03*
X722047D03*
X718897D03*
X715748D03*
X712598D03*
X709448D03*
X706299D03*
X703149D03*
X700000D03*
X734645Y143307D03*
X731496D03*
X728346D03*
X725196D03*
X722047D03*
X718897D03*
X715748D03*
X712598D03*
X709448D03*
X706299D03*
X703149D03*
X700000D03*
X734645Y146456D03*
X731496D03*
X728346D03*
X725196D03*
X722047D03*
X718897D03*
X715748D03*
X712598D03*
X709448D03*
X706299D03*
X703149D03*
X700000D03*
X734645Y149606D03*
X731496D03*
X728346D03*
X725196D03*
X722047D03*
X718897D03*
X715748D03*
X712598D03*
X709448D03*
X706299D03*
X703149D03*
X700000D03*
X734645Y152756D03*
X731496D03*
X728346D03*
X725196D03*
X722047D03*
X718897D03*
X715748D03*
X712598D03*
X709448D03*
X706299D03*
X703149D03*
X700000D03*
X734645Y155905D03*
X731496D03*
X728346D03*
X725196D03*
X722047D03*
X718897D03*
X715748D03*
X712598D03*
X709448D03*
X706299D03*
X703149D03*
X700000D03*
X734645Y159055D03*
X731496D03*
X728346D03*
X725196D03*
X722047D03*
X718897D03*
X715748D03*
X712598D03*
X709448D03*
X706299D03*
X703149D03*
X700000D03*
X734645Y162204D03*
X731496D03*
X728346D03*
X725196D03*
X722047D03*
X718897D03*
X715748D03*
X712598D03*
X709448D03*
X706299D03*
X703149D03*
X700000D03*
X734645Y165354D03*
X731496D03*
X728346D03*
X725196D03*
X722047D03*
X718897D03*
X715748D03*
X712598D03*
X709448D03*
X706299D03*
X703149D03*
X700000D03*
X734645Y168504D03*
X731496D03*
X728346D03*
X725196D03*
X722047D03*
X718897D03*
X715748D03*
X712598D03*
X709448D03*
X706299D03*
X703149D03*
X700000D03*
X734645Y171653D03*
X731496D03*
X728346D03*
X725196D03*
X722047D03*
X718897D03*
X715748D03*
X712598D03*
X709448D03*
X706299D03*
X703149D03*
X700000D03*
X734645Y174803D03*
X731496D03*
X728346D03*
X725196D03*
X722047D03*
X718897D03*
X715748D03*
X712598D03*
X709448D03*
X706299D03*
X703149D03*
X700000D03*
X734645Y177952D03*
X731496D03*
X728346D03*
X725196D03*
X722047D03*
X718897D03*
X715748D03*
X712598D03*
X709448D03*
X706299D03*
X703149D03*
X700000D03*
X734645Y181102D03*
X731496D03*
X728346D03*
X725196D03*
X722047D03*
X718897D03*
X715748D03*
X712598D03*
X709448D03*
X706299D03*
X703149D03*
X700000D03*
X734645Y184252D03*
X731496D03*
X728346D03*
X725196D03*
X722047D03*
X718897D03*
X715748D03*
X712598D03*
X709448D03*
X706299D03*
X703149D03*
X700000D03*
X734645Y187401D03*
X731496D03*
X728346D03*
X725196D03*
X722047D03*
X718897D03*
X715748D03*
X712598D03*
X709448D03*
X706299D03*
X703149D03*
X700000D03*
X734645Y190551D03*
X731496D03*
X728346D03*
X725196D03*
X722047D03*
X718897D03*
X715748D03*
X712598D03*
X709448D03*
X706299D03*
X703149D03*
X700000D03*
X734645Y193700D03*
X731496D03*
X728346D03*
X725196D03*
X722047D03*
X718897D03*
X715748D03*
X712598D03*
X709448D03*
X706299D03*
X703149D03*
X700000D03*
X725196Y196850D03*
X722047D03*
X718897D03*
X715748D03*
X712598D03*
X709448D03*
X706299D03*
X703149D03*
X700000D03*
X725196Y200000D03*
X722047D03*
X718897D03*
X715748D03*
X712598D03*
X709448D03*
X706299D03*
X703149D03*
X700000D03*
X725196Y203149D03*
X722047D03*
X718897D03*
X715748D03*
X712598D03*
X709448D03*
X706299D03*
X703149D03*
X700000D03*
G54D132*
G01X708661Y34646D02*
Y33196D01*
G02X707967Y32502I-694J0D01*
G01X702691D01*
X687991Y47202D01*
Y48050D01*
X686771Y49270D01*
X685923D01*
X684703Y50490D01*
Y51338D01*
X683483Y52558D01*
X682635D01*
X681415Y53778D01*
Y54626D01*
X680195Y55846D01*
X679347D01*
X678127Y57066D01*
Y57914D01*
X676907Y59134D01*
X676059D01*
X673500Y61693D01*
Y68348D01*
X664140Y77708D01*
X645507D01*
X642055Y81160D01*
Y83578D01*
X643492Y85015D01*
Y86686D01*
G01X708661Y29134D02*
Y30584D01*
G03X707968Y31277I-693J0D01*
G01X702183D01*
X672275Y61185D01*
Y67840D01*
X663632Y76483D01*
X644999D01*
X640830Y80652D01*
Y83578D01*
X639392Y85016D01*
Y86686D01*
G01X643442Y94236D02*
Y92248D01*
X643492Y92198D01*
Y90186D01*
G01X643442Y94236D02*
X642055Y95623D01*
Y96141D01*
X654136Y108222D01*
G03X654943Y110172I-1948J1948D01*
G01Y110849D01*
G02X655905Y111811I962J0D01*
G01X639442Y94236D02*
Y92286D01*
X639392Y92236D01*
Y90186D01*
G01X639442Y94236D02*
X640830Y95624D01*
Y96649D01*
X653270Y109089D01*
G03X653718Y110171I-1082J1082D01*
G01Y110849D01*
G03X652756Y111811I-962J0D01*
G01X662204Y114960D02*
X663700Y112522D01*
Y111295D01*
X651456Y99051D01*
Y94146D01*
G03X652031Y93571I575J0D01*
G01X652900D01*
G03X654037Y94708I0J1137D01*
G01X662204Y111811D02*
Y111532D01*
X650231Y99559D01*
Y94146D01*
G03X652031Y92346I1800J0D01*
G01X652899D01*
G02X654037Y91208I0J-1138D01*
G01X665354Y114960D02*
X666742Y113572D01*
Y106855D01*
X658790Y98903D01*
Y94251D01*
G03X659639Y93402I849J0D01*
G01X660910D01*
G03X662047Y94539I0J1137D01*
G01X665354Y111811D02*
X665517Y111648D01*
Y107363D01*
X657565Y99411D01*
Y94251D01*
G03X659639Y92177I2074J0D01*
G01X660909D01*
G02X662047Y91039I0J-1138D01*
G01X671653Y114960D02*
X673041Y113572D01*
Y106673D01*
X666997Y100629D01*
Y94109D01*
G03X667738Y93368I741J0D01*
G01X669009D01*
G03X670146Y94505I0J1137D01*
G01X671653Y111811D02*
X671816Y111648D01*
Y107181D01*
X665772Y101137D01*
Y94109D01*
G03X667738Y92143I1966J0D01*
G01X669008D01*
G02X670146Y91005I0J-1138D01*
G01X674803Y114960D02*
X676191Y113572D01*
Y112156D01*
X676207Y112140D01*
Y104228D01*
X675037Y103058D01*
Y94139D01*
G03X675817Y93359I780J0D01*
G01X677088D01*
G03X678225Y94496I0J1137D01*
G01X674803Y111811D02*
X674982Y111632D01*
Y104736D01*
X673812Y103566D01*
Y94139D01*
G03X675817Y92134I2005J0D01*
G01X677087D01*
G02X678225Y90996I0J-1138D01*
G01X681102Y114960D02*
Y113835D01*
X682490Y112447D01*
Y111098D01*
X682327Y110935D01*
Y103067D01*
X682967Y102427D01*
Y94261D01*
G03X683871Y93357I904J0D01*
G01X685142D01*
G03X686279Y94494I0J1137D01*
G01X681102Y111811D02*
Y102559D01*
X681742Y101919D01*
Y94261D01*
G03X683871Y92132I2129J0D01*
G01X685141D01*
G02X686279Y90994I0J-1138D01*
G01X684252Y114960D02*
Y113848D01*
X685640Y112460D01*
Y107008D01*
X690969Y101679D01*
Y94309D01*
G03X691957Y93321I988J0D01*
G01X693228D01*
G03X694365Y94458I0J1137D01*
G01Y90958D02*
G03X693227Y92096I-1138J0D01*
G01X691957D01*
G02X689744Y94309I0J2213D01*
G01Y101171D01*
X684415Y106500D01*
Y111648D01*
X684252Y111811D01*
G01X690551Y114960D02*
X690777Y114734D01*
Y113661D01*
X692170Y112268D01*
Y107053D01*
X699208Y100015D01*
Y94148D01*
G03X699983Y93373I775J0D01*
G01X701254D01*
G03X702391Y94510I0J1137D01*
G01Y91010D02*
G03X701253Y92148I-1138J0D01*
G01X699983D01*
G02X697983Y94148I0J2000D01*
G01Y99507D01*
X690945Y106545D01*
Y111417D01*
X690551Y111811D01*
G01X693700Y114960D02*
X695088Y113572D01*
Y109779D01*
X701871Y102996D01*
X704414D01*
X707195Y100215D01*
Y96037D01*
G03X707970Y95262I775J0D01*
G01X709241D01*
G03X710378Y96399I0J1137D01*
G01X693700Y111811D02*
X693863Y111648D01*
Y109271D01*
X701363Y101771D01*
X703906D01*
X705970Y99707D01*
Y96037D01*
G03X707970Y94037I2000J0D01*
G01X709240D01*
G02X710378Y92899I0J-1138D01*
G01X662204Y124409D02*
Y124408D01*
X660630Y122834D01*
G01X662204Y121260D02*
X660629Y119685D01*
G01X665354Y124409D02*
X663779Y122834D01*
G01Y119685D02*
X665354Y121260D01*
G01X671653D02*
X670078Y119685D01*
G01X673228D02*
X674803Y121260D01*
G01X681102D02*
X679527Y119685D01*
G01X682677D02*
X684252Y121260D01*
G54D123*
G01X761520Y350206D02*
Y339110D01*
G54D30*
X66403Y133450D03*
X59997D03*
G54D114*
X684769Y452153D03*
Y454712D03*
Y457271D03*
Y459830D03*
Y462389D03*
X704255D03*
Y459830D03*
Y457271D03*
Y454712D03*
Y452153D03*
G54D21*
X52607Y171752D03*
X56607D03*
X72800Y186600D03*
X25900Y207000D03*
X65500Y234500D03*
X45938Y235404D03*
X41938D03*
X64100Y187800D03*
X46500Y186900D03*
X50500D03*
X26600Y278900D03*
X27200Y305200D03*
X65500Y375500D03*
X22000Y375052D03*
X43000Y374933D03*
X73100Y375500D03*
X29900Y375052D03*
X50700Y374933D03*
X87300Y227100D03*
X89800Y186800D03*
X85795Y375126D03*
X93695D03*
X89600Y394600D03*
X195161Y131517D03*
X201139Y118095D03*
X156700Y136200D03*
X250791Y69127D03*
X238880Y70262D03*
X220227Y70215D03*
X238900Y287900D03*
X245800Y288000D03*
X219400Y287400D03*
X226600Y287900D03*
X260000D03*
X240200Y306800D03*
X258700Y304300D03*
X222000Y306700D03*
X255500Y419200D03*
X318050Y296600D03*
X267600Y287900D03*
X285400Y320800D03*
X283000Y409200D03*
X269500Y420200D03*
X343000Y305700D03*
X345121Y331450D03*
X370932Y323700D03*
X326083Y412566D03*
X412400Y343784D03*
X437500Y344200D03*
X427700Y344000D03*
X400300Y345100D03*
X469996Y354412D03*
X451400Y344200D03*
X460327Y344201D03*
X464327D03*
X482427Y358374D03*
X486627D03*
X497900Y345300D03*
X502700D03*
X507337Y345263D03*
X478298Y358254D03*
X480700Y344200D03*
X522000Y354850D03*
X512754Y345184D03*
X573570Y463680D03*
X590350Y330450D03*
X618900Y322800D03*
X631800Y322700D03*
X629370Y460030D03*
X586720Y476380D03*
X664301Y35265D03*
X664000Y57200D03*
X643492Y90136D03*
X639392D03*
X682700Y237200D03*
X695600D03*
X695100Y381700D03*
X675831Y396033D03*
X670610Y418830D03*
X675380Y457860D03*
X667900Y446600D03*
X755523Y93515D03*
X751023D03*
X699600Y237200D03*
X743600Y224400D03*
X739500D03*
X734286Y224423D03*
X726656Y231898D03*
X719300Y220900D03*
X759651Y266807D03*
X751470Y310720D03*
X700200Y381700D03*
X763840Y266710D03*
X782800Y328170D03*
G54D105*
G01X36850Y393440D02*
X31240D01*
G01X43350Y398560D02*
X49290D01*
X49700Y398150D01*
G01X83232Y399956D02*
X82156D01*
X80155Y397955D01*
X77257D01*
G01X284498Y304389D02*
Y299976D01*
G01X446850Y281497D02*
X444882Y279529D01*
G01X446850Y261811D02*
X448818Y259843D01*
G01X446850Y269686D02*
X448818Y267718D01*
G01X438976Y269686D02*
X440944Y267718D01*
G01X433071Y263781D02*
X435039Y265749D01*
G01X442913Y257874D02*
X440944Y259843D01*
G01X446850Y269686D02*
X442913Y273623D01*
G01X450787D02*
X446850Y277560D01*
G01X442913Y273623D02*
X438976Y277560D01*
G01X440944Y259843D02*
X438976Y261811D01*
G01X440944Y267718D02*
X442913Y265749D01*
G01X448818Y267718D02*
X450787Y265749D01*
G01X448818Y259843D02*
X450787Y257874D01*
G01X444882Y279529D02*
X446850Y277561D01*
Y277560D01*
G01X437057Y279414D02*
X438976Y281333D01*
Y281497D01*
G01X433071Y275591D02*
X431102Y277560D01*
G01Y261811D02*
Y261812D01*
X433071Y263781D01*
G01X435039Y257874D02*
X433070Y255905D01*
G01X427165Y265749D02*
X426527Y265111D01*
Y262449D01*
X427165Y261811D01*
G01X446850Y257874D02*
X448818Y255906D01*
G01X450787Y261811D02*
X448818Y263780D01*
G01X446850Y273623D02*
X448818Y271655D01*
G01X442913Y261811D02*
X440944Y263780D01*
G01X435039Y269686D02*
X437007Y267718D01*
G01X438976Y273623D02*
X440944Y271655D01*
G01X437007Y259843D02*
X435039Y261811D01*
G01X437007Y255905D02*
X435039Y253937D01*
G01X442913D02*
X440944Y255906D01*
G01X442913Y277560D02*
X444882Y275591D01*
G01X435039Y277560D02*
X437008Y275591D01*
G01X440944Y255906D02*
X438976Y257874D01*
G01X440944Y271655D02*
X442913Y269686D01*
G01X440944Y263780D02*
X438976Y265748D01*
Y265749D01*
G01X448818Y271655D02*
X450787Y269686D01*
G01X448818Y263780D02*
X446850Y265748D01*
Y265749D01*
G01X448818Y255906D02*
X450787Y253937D01*
G01X437007Y267718D02*
X438976Y265749D01*
G01X466536D02*
X464567Y267718D01*
G01X462599Y281497D02*
X464567Y279529D01*
G01X466536Y257874D02*
X464567Y259843D01*
G01X454725Y269686D02*
X456693Y267718D01*
G01X454725Y269686D02*
X454724D01*
X450787Y273623D01*
G01X458662D02*
X462599Y269686D01*
G01X454725Y277560D02*
X458662Y273623D01*
G01X464567Y259843D02*
X462599Y261811D01*
G01X464567Y279529D02*
X462599Y277561D01*
Y277560D01*
G01X456693Y259843D02*
X458662Y257874D01*
G01X464567Y267718D02*
X462599Y269686D01*
G01X456693Y267718D02*
X458662Y265749D01*
G01X454725Y261811D02*
X456693Y259843D01*
G01X454725Y257874D02*
X456693Y255906D01*
G01X462599Y257874D02*
X464567Y255906D01*
G01X466536Y261811D02*
X464567Y263780D01*
G01X458662Y261811D02*
X456693Y263780D01*
G01X462599Y273623D02*
X464567Y271655D01*
G01X458662Y269686D02*
X456693Y271655D01*
G01X466536Y277560D02*
X464568Y275592D01*
G01X458662Y277560D02*
X460630Y275592D01*
G01X452756D02*
X450788Y277560D01*
X450787D01*
G01X456693Y271655D02*
X454725Y273623D01*
G01X464567Y271655D02*
X466536Y269686D01*
G01X456693Y263780D02*
X454725Y265748D01*
Y265749D01*
G01X464567Y263780D02*
X462599Y265748D01*
Y265749D01*
G01X464567Y255906D02*
X466536Y253937D01*
G01X456693Y255906D02*
X458662Y253937D01*
G01X513780Y234252D02*
X517000D01*
G01Y218500D02*
X516996Y218504D01*
X513780D01*
G01X517000Y226370D02*
X516992Y226378D01*
X513780D01*
X649606Y111811D03*
X646456D03*
X649606Y114960D03*
X646456D03*
X643307D03*
X649606Y118110D03*
X646456D03*
X643307D03*
X649606Y196850D03*
X646456D03*
X643307D03*
X649606Y200000D03*
X646456D03*
X643307D03*
X649606Y203149D03*
X646456D03*
X731496Y111811D03*
X728346D03*
X734645Y114960D03*
X731496D03*
X728346D03*
X734645Y118110D03*
X731496D03*
X728346D03*
X734645Y196850D03*
X731496D03*
X728346D03*
X734645Y200000D03*
X731496D03*
X728346D03*
X731496Y203149D03*
X728346D03*
G54D12*
G01X660100Y299400D02*
Y287369D01*
X622400Y249669D01*
Y216750D01*
G01X620499Y272162D02*
X616872Y268535D01*
X592256D01*
X585791Y275000D01*
Y422519D01*
X584280Y424030D01*
G01X635000Y433700D02*
Y427784D01*
G01X707574Y276558D02*
X665058D01*
X660400Y271900D01*
G01X749900Y293200D02*
X731797D01*
X709183Y270586D01*
X677222D01*
X675136Y268500D01*
X37700Y64400D03*
X86150Y441700D03*
X365450Y179154D03*
X552000Y368500D03*
X630600Y221100D03*
X762300Y106300D03*
X737400Y485700D03*
G54D124*
G01X655905Y118110D02*
X657479Y116536D01*
G54D106*
X684800Y313200D03*
X695800D03*
X720383Y412014D03*
X709383D03*
X720383Y403014D03*
X709383D03*
G54D40*
X61790Y199650D03*
X48010D03*
Y219750D03*
X61790D03*
G54D115*
X697071Y447528D03*
X694512D03*
X691953D03*
X689394D03*
Y467014D03*
X691953D03*
X694512D03*
X697071D03*
X699630Y447528D03*
Y467014D03*
G54D22*
X52607Y168352D03*
X56607D03*
X72800Y183200D03*
X25900Y203600D03*
X65500Y231100D03*
X45938Y232004D03*
X41938D03*
X64100Y184400D03*
X46500Y183500D03*
X50500D03*
X26600Y275500D03*
X27200Y301800D03*
X65500Y372100D03*
X22000Y371652D03*
X43000Y371533D03*
X73100Y372100D03*
X29900Y371652D03*
X50700Y371533D03*
X87300Y223700D03*
X89800Y183400D03*
X85795Y371726D03*
X93695D03*
X89600Y391200D03*
X195161Y128117D03*
X201139Y114695D03*
X156700Y132800D03*
X250791Y65727D03*
X238880Y66862D03*
X220227Y66815D03*
X238900Y284500D03*
X245800Y284600D03*
X219400Y284000D03*
X226600Y284500D03*
X260000D03*
X240200Y303400D03*
X258700Y300900D03*
X222000Y303300D03*
X255500Y415800D03*
X318050Y293200D03*
X267600Y284500D03*
X285400Y317400D03*
X283000Y405800D03*
X269500Y416800D03*
X343000Y302300D03*
X345121Y328050D03*
X370932Y320300D03*
X326083Y409166D03*
X412400Y340384D03*
X437500Y340800D03*
X427700Y340600D03*
X400300Y341700D03*
X469996Y351012D03*
X451400Y340800D03*
X460327Y340801D03*
X464327D03*
X482427Y354974D03*
X486627D03*
X497900Y341900D03*
X502700D03*
X507337Y341863D03*
X478298Y354854D03*
X480700Y340800D03*
X522000Y351450D03*
X512754Y341784D03*
X573570Y460280D03*
X590350Y327050D03*
X618900Y319400D03*
X631800Y319300D03*
X629370Y456630D03*
X586720Y472980D03*
X664301Y31865D03*
X664000Y53800D03*
X643492Y86736D03*
X639392D03*
X682700Y233800D03*
X695600D03*
X695100Y378300D03*
X675831Y392633D03*
X670610Y415430D03*
X675380Y454460D03*
X667900Y443200D03*
X755523Y90115D03*
X751023D03*
X699600Y233800D03*
X743600Y221000D03*
X739500D03*
X734286Y221023D03*
X726656Y228498D03*
X719300Y217500D03*
X759651Y263407D03*
X751470Y307320D03*
X700200Y378300D03*
X763840Y263310D03*
X782800Y324770D03*
G54D13*
X53100Y152000D03*
X27000Y292200D03*
Y287700D03*
X61867Y242333D03*
X41500Y266100D03*
X27300Y318500D03*
Y314000D03*
X57400Y403150D03*
X85600Y194900D03*
X84100Y213800D03*
X160100Y113400D03*
X156600Y122000D03*
X160100Y117700D03*
X255300Y90000D03*
Y95000D03*
X207800Y284000D03*
X296435Y104177D03*
X277300Y321600D03*
X270668Y378200D03*
Y382200D03*
X274769Y373425D03*
X369300Y279500D03*
X362800Y293000D03*
X369300Y275500D03*
X369100Y283900D03*
X349800Y308000D03*
X358300Y340500D03*
X370800Y344500D03*
X361327Y312654D03*
X370982Y328503D03*
X340550Y309823D03*
X326638Y405044D03*
X388949Y340563D03*
X470397Y358638D03*
X527915Y335679D03*
Y331679D03*
X635992Y94236D03*
X629300Y278745D03*
X593800Y346950D03*
X597723Y352729D03*
Y356729D03*
X600587Y322456D03*
Y326656D03*
X622350Y348900D03*
X619850Y353400D03*
X622350Y310491D03*
X619850Y314991D03*
X611850D03*
X612350Y353400D03*
X597373Y378955D03*
Y374955D03*
X617067Y378894D03*
Y374894D03*
X586600Y486650D03*
X581000Y460300D03*
X581070Y468530D03*
X643492Y94236D03*
X668231Y392433D03*
X672800Y407500D03*
X646020Y395300D03*
X743500Y94500D03*
X728531Y98293D03*
X736000Y86200D03*
Y90300D03*
X743500Y86300D03*
Y90400D03*
X757471Y143624D03*
X757450Y139500D03*
X753600Y169550D03*
X758500Y135400D03*
X750408Y154100D03*
X750400Y160050D03*
X750423Y148245D03*
X753602Y173715D03*
X751268Y164081D03*
X753618Y179053D03*
X753630Y197200D03*
X711800Y217500D03*
X753618Y183153D03*
Y187253D03*
X753630Y206200D03*
X747270Y297120D03*
X754183Y317184D03*
X725270Y423930D03*
X728200Y475400D03*
X794770Y307120D03*
Y302620D03*
G54D31*
G01X-34018Y-300855D02*
G02I-12000J0D01*
G01X-39168D02*
G02I-6850J0D01*
G01X-30018D02*
X-62018D01*
G01X-30018Y-316855D02*
Y-396855D01*
G01D02*
X1320682D01*
G01X-30018Y-352355D02*
X1320682D01*
G01X-46018Y-316855D02*
Y-284855D01*
G01X-30018Y-316855D02*
X1320682D01*
G01X26500Y156750D02*
X22550D01*
G01X56550Y152000D02*
X59600D01*
G01X52400Y234550D02*
Y237800D01*
G01X32405Y187767D02*
X28455D01*
G01X32699Y191548D02*
X28749D01*
G01X33700Y226950D02*
Y230600D01*
G01X26150Y223500D02*
X22250D01*
G01X26500Y217500D02*
X21910D01*
G01X65500Y234550D02*
Y237800D01*
G01X75350Y221000D02*
X78850D01*
G01X70500Y234550D02*
Y237800D01*
G01X75500Y234550D02*
Y237800D01*
G01X59800Y182900D02*
Y178700D01*
X59700Y178600D01*
G01X68400Y181900D02*
Y177950D01*
G01X76800Y183150D02*
Y178200D01*
G01X72300Y202400D02*
X76500D01*
G01X82800Y204400D02*
X80800Y202400D01*
X76500D01*
G01X59800Y193700D02*
Y188900D01*
G01X64100Y187850D02*
X60850D01*
X59800Y188900D01*
G01X64100Y184350D02*
Y178500D01*
X64000Y178400D01*
G01X72800Y183150D02*
Y178200D01*
G01X25900Y203550D02*
X22150D01*
G01X26150Y227500D02*
Y230850D01*
G01X56026Y250139D02*
Y256117D01*
G01X26950Y292200D02*
X23100D01*
G01X26950Y287700D02*
X23100D01*
G01X26950Y283200D02*
X23100D01*
G01X26600Y275450D02*
X22750D01*
G01X74150Y291700D02*
X73650Y292200D01*
X68300D01*
G01D02*
X62500D01*
G01X26950Y296700D02*
X23500D01*
G01X44950Y266100D02*
Y261900D01*
G01X40290Y239814D02*
Y249390D01*
X44950Y254050D01*
Y261900D01*
G01X27947Y334066D02*
Y335902D01*
X27950Y335905D01*
Y337800D01*
G01X47443Y334198D02*
X48950Y335705D01*
Y337600D01*
G01X69143Y334598D02*
X70650Y336105D01*
Y338000D01*
G01X37049Y302949D02*
X39022Y304922D01*
X42404D01*
G01X31400Y301750D02*
X35850D01*
X37049Y302949D01*
G01X27250Y318500D02*
X23100D01*
G01X27250Y314000D02*
X23100D01*
G01X52450Y337600D02*
Y333850D01*
G01X31450Y337800D02*
Y334050D01*
G01X74150Y338000D02*
Y334250D01*
G01X23400Y309500D02*
X27250D01*
G01X27200Y301750D02*
X24000D01*
G01X28000Y326500D02*
X27250Y325750D01*
Y323000D01*
G01X26100Y375102D02*
Y378352D01*
G01X46900Y374983D02*
Y378233D01*
G01X69300Y375550D02*
Y378800D01*
G01X57350Y391050D02*
Y387800D01*
G01X49700Y394650D02*
Y391000D01*
G01X50250Y387500D02*
Y390450D01*
X49700Y391000D01*
G01X57330Y399390D02*
X54040D01*
G01X57350Y403150D02*
X53500D01*
G01X49700Y402000D02*
Y398150D01*
G01X50700Y374983D02*
Y378233D01*
G01X54800Y370150D02*
Y373600D01*
G01X29900Y375102D02*
Y378252D01*
G01X38200Y370350D02*
Y373800D01*
G01X34100Y370350D02*
Y373800D01*
G01X73100Y375550D02*
Y378700D01*
G01X60400Y370150D02*
Y373600D01*
G01X60850Y391050D02*
X63590D01*
X65375Y392835D01*
G01X88800Y199400D02*
X92300D01*
G01X88800Y209400D02*
X92300D01*
G01X88800Y204400D02*
X92300D01*
G01X87550Y217900D02*
X90800D01*
G01X82600Y228500D02*
Y232000D01*
G01X87300Y227150D02*
Y230650D01*
G01X89050Y190900D02*
X92300D01*
G01X81300Y182000D02*
Y178050D01*
G01X85700Y183350D02*
Y178000D01*
G01X89050Y194900D02*
X92300D01*
G01X78800Y205900D02*
X81300D01*
X82800Y204400D01*
G01X92300Y213900D02*
X94600Y216200D01*
Y225450D01*
X92900Y227150D01*
X91300D01*
G01X87550Y213800D02*
X92200D01*
X92300Y213900D01*
G01X89800Y178000D02*
Y183350D01*
G01X77650Y291700D02*
X81000D01*
G01X77546Y286695D02*
X80896D01*
G01X90238Y334391D02*
X91745Y335898D01*
Y337793D01*
G01X95245D02*
Y334043D01*
G01X89895Y375176D02*
Y378426D01*
G01X102395Y370343D02*
Y373793D01*
G01X93695Y375176D02*
Y378426D01*
G01X81300Y370550D02*
Y374000D01*
G01X77200Y370550D02*
Y374000D01*
G01X98295Y370343D02*
Y373793D01*
G01X99400Y452650D02*
X102850D01*
G01X187050Y110000D02*
X191000D01*
G01X160050Y113400D02*
X152800D01*
G01X156550Y122000D02*
Y124583D01*
X158612Y126645D01*
G01X198202Y135298D02*
X193264D01*
G01D02*
X195161Y133401D01*
Y131567D01*
G01X149100Y136500D02*
X145900D01*
G01X196963Y118544D02*
Y122029D01*
G01X201139Y118145D02*
Y121630D01*
G01X164810Y143681D02*
Y139832D01*
X165097Y139545D01*
G01X164810Y151500D02*
Y147181D01*
G01X169800Y150000D02*
X168500D01*
X167000Y151500D01*
X164810D01*
G01X176500Y169600D02*
Y161200D01*
G01D02*
Y156800D01*
X175300Y155600D01*
Y144500D01*
G01X184700Y159000D02*
X178800Y153100D01*
Y144500D01*
G01X184700Y159000D02*
X186700Y157000D01*
X207200D01*
X208100Y157900D01*
Y161900D01*
G01X172800Y141001D02*
X172799Y141000D01*
X171500D01*
X169800Y142700D01*
Y144000D01*
G01X180300Y175400D02*
X180400Y175500D01*
X185789D01*
G01X176500Y175600D02*
Y179400D01*
X177550Y180450D01*
G01X194657Y153196D02*
X198557D01*
G01X185789Y180500D02*
X177600D01*
X177550Y180450D01*
G01X200250Y298800D02*
X197100D01*
G01X503800Y382700D02*
X323200D01*
X285570Y345070D01*
X208970D01*
X188700Y324800D01*
X177850D01*
G01X200250Y306800D02*
X196600D01*
G01X225750Y95000D02*
X229000D01*
G01X231250Y73000D02*
X234450D01*
G01X245250Y95000D02*
Y98250D01*
G01X223995Y66741D02*
X223994Y66740D01*
Y63225D01*
G01X242733Y66761D02*
Y63397D01*
X242727Y63391D01*
G01X241750Y95000D02*
Y98250D01*
G01X238880Y66812D02*
X238867Y66799D01*
Y63650D01*
G01X214350Y81543D02*
Y92848D01*
X216502Y95000D01*
X222250D01*
G01X214350Y81543D02*
Y68818D01*
X216403Y66765D01*
X220227D01*
G01D02*
Y63652D01*
X220228Y63651D01*
G01X208011Y175500D02*
X211500D01*
X213400Y173600D01*
Y169500D01*
X211800Y167900D01*
X208100D01*
G01X204644Y209985D02*
X206915D01*
X210500Y206400D01*
G01X207650Y287800D02*
Y292350D01*
X207600Y292400D01*
G01X249095Y279732D02*
X248863Y279500D01*
X246100D01*
X245800Y279200D01*
G01D02*
X245300Y279700D01*
X242550D01*
G01X207750Y284000D02*
X206000D01*
X204400Y285600D01*
Y288700D01*
G01X248900Y282932D02*
X247418D01*
X245800Y284550D01*
G01X252000Y284450D02*
X250482Y282932D01*
X248900D01*
G01X260000Y284450D02*
Y281371D01*
X259629Y281000D01*
G01X238900Y284450D02*
X240450Y282900D01*
X242351D01*
G01X219400Y283950D02*
Y279400D01*
G01X218500Y320200D02*
Y317550D01*
X217950Y317000D01*
G01X235500Y320100D02*
Y317050D01*
X235350Y316900D01*
G01X253725Y316967D02*
Y320017D01*
X253575Y320167D01*
G01X231700Y320100D02*
Y317050D01*
X231850Y316900D01*
G01X250225Y316967D02*
Y319717D01*
X249775Y320167D01*
G01X214700Y320200D02*
Y317250D01*
X214450Y317000D01*
G01X263250Y412100D02*
X266300D01*
G01X260720Y376270D02*
Y371840D01*
X261581Y370979D01*
G01X226700Y394954D02*
Y397500D01*
X226200Y398000D01*
Y400600D01*
G01D02*
Y404650D01*
G01X274250Y29000D02*
X270000D01*
G01X274250Y33500D02*
X270000D01*
G01X274250Y38000D02*
X270000D01*
G01X274250Y42500D02*
X270000D01*
G01X296385Y104177D02*
Y108227D01*
G01X270143Y276969D02*
X272270D01*
X273634Y278333D01*
X275576D01*
G01X318050Y293150D02*
Y291652D01*
X319543Y290159D01*
G01X303032Y289900D02*
Y308232D01*
X322800Y328000D01*
X345121D01*
G01X273165Y320351D02*
Y317201D01*
X273115Y317151D01*
G01X294850Y328300D02*
Y325600D01*
X294250Y325000D01*
G01X277150Y328400D02*
Y332000D01*
G01X280650Y328400D02*
Y325150D01*
X280800Y325000D01*
G01X280750Y321600D02*
Y324950D01*
X280800Y325000D01*
G01X291350Y328300D02*
Y326900D01*
X290750Y326300D01*
Y325000D01*
G01X291450Y321700D02*
Y322550D01*
X290750Y323250D01*
Y325000D01*
G01X269365Y320351D02*
Y317401D01*
X269615Y317151D01*
G01X335701Y219461D02*
Y223995D01*
G01X341757Y211056D02*
Y215563D01*
G01X344891Y206090D02*
X337195D01*
X337157Y206052D01*
G01X374250Y303200D02*
Y299200D01*
G01X365387Y261459D02*
X368389D01*
X368714Y261134D01*
G01X372119Y261330D02*
X368910D01*
X368714Y261134D01*
G01X327868Y290125D02*
X331730D01*
X332750Y289105D01*
G01X369250Y275500D02*
X368655D01*
X365996Y272841D01*
G01X369050Y288000D02*
X366731D01*
X365996Y287265D01*
G01X369050Y283900D02*
Y288000D01*
G01X362750Y299200D02*
Y293000D01*
G01Y303200D02*
Y299200D01*
G01X369250Y279500D02*
X364655D01*
X357996Y272841D01*
G01X370750Y344500D02*
Y347100D01*
X370250Y347600D01*
G01X374250Y303200D02*
X376968D01*
X377324Y302844D01*
G01X359400Y347200D02*
X359100Y347500D01*
X354250D01*
G01X360050Y334000D02*
Y337200D01*
G01X345150Y323900D02*
X348600D01*
G01X358250Y340500D02*
Y342850D01*
X359400Y344000D01*
Y347200D01*
G01X375148Y337184D02*
Y332716D01*
X374432Y332000D01*
Y328503D01*
G01X374250Y340500D02*
Y338082D01*
X375148Y337184D01*
G01X384000Y341000D02*
Y338600D01*
X382600Y337200D01*
G01X344000Y316000D02*
Y309823D01*
G01X346500Y302500D02*
X359500D01*
X360200Y303200D01*
X362750D01*
G01X343000Y302250D02*
X346250D01*
X346500Y302500D01*
G01X374432Y316002D02*
X371084Y312654D01*
X364777D01*
G01X356550Y334000D02*
Y337200D01*
G01X345121Y328000D02*
X350550D01*
X356550Y334000D01*
G01X337900Y427750D02*
Y431200D01*
G01X325651Y439668D02*
X328958D01*
G01X325629Y443510D02*
X328936D01*
G01X395669Y210630D02*
X393701Y208662D01*
G01X391732Y206693D02*
X389764Y204725D01*
G01X391732Y210630D02*
X389764Y208662D01*
G01X399606Y202756D02*
X397638Y200788D01*
G01X399606Y324804D02*
X397638Y326772D01*
G01X399606Y316930D02*
X397638Y318898D01*
G01X388899Y340563D02*
Y337763D01*
X389559Y337103D01*
G01X416841Y343834D02*
Y347114D01*
X416822Y347133D01*
G01X412400Y343834D02*
Y347130D01*
X412381Y347149D01*
G01X435000Y347800D02*
X437500Y345300D01*
Y344250D01*
G01X433964Y356373D02*
X435000Y355337D01*
Y347800D01*
G01X447300Y344250D02*
Y345650D01*
X445150Y347800D01*
X441000D01*
G01X427700Y344050D02*
Y345842D01*
X426464Y347078D01*
G01X400300Y341650D02*
Y340300D01*
X397000Y337000D01*
G01X505906Y210630D02*
X507874Y208662D01*
G01X505906Y206693D02*
X507874Y204725D01*
G01X509843Y210630D02*
X511811Y208662D01*
G01X505906Y202756D02*
X507874Y200788D01*
G01X509843Y202756D02*
X511811Y200788D01*
G01Y208662D02*
X513779Y210630D01*
X513780D01*
G01X505906Y316930D02*
X507874Y318898D01*
G01X480700Y344250D02*
Y347068D01*
X481359Y347727D01*
G01X482427Y358424D02*
X486627D01*
G01D02*
Y360327D01*
X490000Y363700D01*
G01X485100Y363400D02*
X484300D01*
X483300Y362400D01*
X481750D01*
G01X472296Y344250D02*
X476500D01*
G01Y347650D02*
Y344250D01*
G01X474150Y350800D02*
Y350000D01*
X476500Y347650D01*
G01X506200Y355750D02*
Y358809D01*
G01X493200Y355750D02*
Y358800D01*
G01X499700Y355750D02*
Y358209D01*
X498700Y359209D01*
G01X481750Y366800D02*
X485100D01*
G01X533182Y-316855D02*
Y-396855D01*
G01X513780Y316930D02*
X515748Y318898D01*
G01X547315Y335238D02*
Y338288D01*
X547379Y338352D01*
G01X551394Y335238D02*
X547315D01*
G01X541714Y335253D02*
Y336486D01*
X539900Y338300D01*
G01X534000Y338400D02*
X535336Y337064D01*
Y335272D01*
G01X531365Y335679D02*
Y335765D01*
X534000Y338400D01*
G01X531365Y331679D02*
Y335679D01*
G01X528894Y351065D02*
X526003D01*
X525438Y350500D01*
G01X528894Y351065D02*
X532894D01*
G01X522000Y354900D02*
X518000D01*
G01D02*
Y356900D01*
X515691Y359209D01*
X514000D01*
G01D02*
Y355050D01*
G01X623566Y173443D02*
X618400D01*
G01X627455Y185364D02*
Y179508D01*
X627464Y179499D01*
G01X618300Y288745D02*
X621750D01*
G01X632750Y292195D02*
Y288745D01*
G01Y295641D02*
Y299091D01*
G01X597287Y284017D02*
X594025D01*
G01X632750Y278745D02*
X644153D01*
G01X597287Y280017D02*
X594025D01*
G01X629200Y302891D02*
X629250Y302841D01*
Y299091D01*
G01X612300Y356850D02*
Y353400D01*
G01X632750Y334300D02*
Y337500D01*
G01Y330854D02*
Y327654D01*
G01X621750D02*
X618300D01*
G01X632800Y302891D02*
Y305100D01*
X634000Y306300D01*
G01X632800Y341500D02*
Y344850D01*
X632900Y344950D01*
G01X611800Y314991D02*
X608509D01*
X608500Y315000D01*
G01X593750Y334350D02*
X590200D01*
G01X593750Y337900D02*
X590100D01*
X590050Y337950D01*
G01X631800Y319250D02*
Y316137D01*
G01X603650Y315500D02*
X606606Y318456D01*
X618006D01*
X618900Y319350D01*
G01X594292Y362291D02*
X594792Y362791D01*
X598152D01*
G01X625000Y361700D02*
Y361614D01*
X626014Y360600D01*
X629564D01*
X630578Y361614D01*
Y364424D01*
G01X590350Y327000D02*
Y323011D01*
G01X626405Y314991D02*
X623300D01*
G01X629250Y310491D02*
X625800D01*
G01X629250Y344900D02*
Y341450D01*
G01X629200Y341500D02*
X629250Y341450D01*
G01Y348900D02*
X625800D01*
G01X629250Y341450D02*
Y337500D01*
G01Y306491D02*
Y302941D01*
X629200Y302891D01*
G01X597250Y346950D02*
X599343Y349043D01*
X602639D01*
X602649Y349033D01*
G01X623063Y357337D02*
X623300Y357100D01*
Y353400D01*
G01X626320Y369320D02*
X629770D01*
G01X598152Y370130D02*
Y366291D01*
G01X627020Y389940D02*
Y393364D01*
G01X594200Y390400D02*
X594639Y389961D01*
X598023D01*
G01Y383081D02*
Y386461D01*
G01X591920Y426720D02*
X587890D01*
G01X626300Y464900D02*
Y462760D01*
X624770Y461230D01*
G01X581020Y468530D02*
Y471890D01*
G01X580950Y460300D02*
X577300D01*
G01X591940Y430440D02*
X588385D01*
X588030Y430795D01*
G01X670682Y-316855D02*
Y-396855D01*
G01X635942Y94236D02*
Y97351D01*
G01X648207Y70750D02*
X652625D01*
G01X646942Y94236D02*
Y97560D01*
X646643Y97859D01*
G01X682700Y237250D02*
Y240354D01*
G01X695600Y237250D02*
Y240354D01*
G01X699600Y237250D02*
X695600D01*
G01X678500D02*
Y240324D01*
G01X691100Y237250D02*
Y240354D01*
G01X686900Y237250D02*
Y240354D01*
G01X667353Y230382D02*
Y233486D01*
G01X645968Y230547D02*
X641672D01*
X641579Y230640D01*
G01X650287Y230524D02*
X645991D01*
X645968Y230547D01*
G01X654464Y230565D02*
X650328D01*
X650287Y230524D01*
G01X663110Y230425D02*
X658610D01*
G01X667353Y230382D02*
X663153D01*
X663110Y230425D01*
G01X658610D02*
X654604D01*
X654464Y230565D01*
G01X641579Y230640D02*
X638479D01*
G01X669033Y347018D02*
Y350751D01*
X667617Y352167D01*
G01X642900Y395400D02*
Y394100D01*
X643460Y393540D01*
Y390820D01*
G01X694765Y411520D02*
Y406915D01*
G01X681540Y419460D02*
X685750D01*
G01X690500Y377500D02*
Y376300D01*
X693500Y373300D01*
G01X687581Y395883D02*
Y396969D01*
X686581Y397969D01*
X686531D01*
X684400Y400100D01*
G01X672750Y407500D02*
Y410100D01*
X674150Y411500D01*
Y415380D01*
G01X670610D02*
X674150D01*
G01X654770Y398110D02*
Y401166D01*
G01X686300Y371300D02*
X682860D01*
X682000Y372160D01*
G01X663706Y423000D02*
Y435706D01*
X667900Y439900D01*
Y443150D01*
G01X653200Y408800D02*
X663706Y419306D01*
Y423000D01*
G01X672800Y438832D02*
Y442400D01*
G01X692200Y428700D02*
X686770D01*
X686390Y428320D01*
G01X681540Y425460D02*
Y429640D01*
G01X682350Y440950D02*
X678700D01*
G01X745100Y97500D02*
X741590D01*
X740590Y98500D01*
X735898D01*
X735691Y98293D01*
X731981D01*
G01X746950Y90400D02*
Y94500D01*
G01D02*
Y95650D01*
X745100Y97500D01*
G01X760600Y173700D02*
X760450D01*
X760435Y173715D01*
X757052D01*
G01X754718Y164081D02*
X754739D01*
X754770Y164050D01*
X758050D01*
G01X757050Y169550D02*
X760800D01*
G01X753873Y148245D02*
X757419D01*
X757471Y148193D01*
G01X753850Y160050D02*
X761400D01*
G01X753858Y154100D02*
X763050D01*
G01X757080Y210200D02*
X760715D01*
G01X726656Y231948D02*
Y235244D01*
G01X757080Y201700D02*
X760715D01*
G01X739500Y224450D02*
X743600D01*
G01X757080Y214200D02*
X760715D01*
G01X719300Y220950D02*
X722158D01*
X722523Y221315D01*
G01X743600Y224450D02*
Y227500D01*
X743200Y227900D01*
G01X730694Y224473D02*
X734286D01*
G01X730712Y231957D02*
X730737Y231982D01*
Y235199D01*
G01X724465Y224741D02*
X725750Y223456D01*
Y221022D01*
G01X715250Y217500D02*
Y220411D01*
X714620Y221041D01*
G01X738786Y231973D02*
X743387D01*
X743460Y231900D01*
G01X712720Y237872D02*
Y240976D01*
G01X750358Y280164D02*
Y278337D01*
X751878Y276817D01*
G01X753858Y290786D02*
Y280164D01*
G01X751470Y310770D02*
Y313647D01*
X751133Y313984D01*
G01X754133Y317184D02*
X752504D01*
X751133Y315813D01*
Y313984D01*
G01X754227Y301111D02*
X757488D01*
G01X750720Y301620D02*
X753718D01*
X754227Y301111D01*
G01X765764Y326844D02*
X757844D01*
X754133Y323133D01*
Y321684D01*
G01D02*
X752208D01*
X746970Y316446D01*
Y310770D01*
G01X709075Y420610D02*
X705320D01*
G01X725220Y423930D02*
X721380D01*
G01X718100Y446230D02*
X718110Y446220D01*
Y442960D01*
G01X723725Y429970D02*
X720190D01*
X719920Y429700D01*
G01X735570Y427980D02*
Y424760D01*
G01X701120Y433870D02*
Y430620D01*
G01X710200Y437980D02*
Y441200D01*
G01X727840Y447430D02*
Y449270D01*
X729870Y451300D01*
G01X731992Y447367D02*
Y449178D01*
X729870Y451300D01*
G01X785682Y-316855D02*
Y-396855D01*
G01X769600Y164200D02*
X766050D01*
G01X760921Y143624D02*
X762476D01*
X764600Y141500D01*
G01X760900Y139500D02*
X762600D01*
X764600Y141500D01*
G01X761950Y135400D02*
X764850D01*
X765200Y135750D01*
G01X781640Y278660D02*
X778440D01*
G01X797155Y297017D02*
X793915D01*
X793912Y297020D01*
G01X781640Y282160D02*
X778440D01*
G01X805300Y267250D02*
Y263840D01*
X805254Y263886D01*
G01X786560Y324680D02*
Y321390D01*
X786610Y321340D01*
G01X782800Y324720D02*
Y321230D01*
X782770Y321200D01*
G01X953182Y-316855D02*
Y-396855D01*
G01X1123182Y-316855D02*
Y-396855D01*
G01X1320682Y-316855D02*
Y-396855D01*
G01X1348682Y-300855D02*
G02I-12000J0D01*
G01X1343532D02*
G02I-6850J0D01*
G01X1336682Y-316855D02*
Y-284855D01*
G01X1352682Y-300855D02*
X1320682D01*
X22550Y156750D03*
X54697Y165269D03*
X58697D03*
X59600Y152000D03*
X71200Y137200D03*
X52400Y237800D03*
X28455Y187767D03*
X28749Y191548D03*
X39301Y203166D03*
X33700Y230600D03*
X21910Y217500D03*
X22250Y223500D03*
X39416Y206616D03*
X65500Y237800D03*
X70500D03*
X75500D03*
X23800Y211200D03*
X27500D03*
X59700Y178600D03*
X68400Y177950D03*
X76800Y178200D03*
X46194Y179835D03*
X50194D03*
X39320Y213823D03*
X64000Y178400D03*
X72800Y178200D03*
X22150Y203550D03*
X26150Y230850D03*
X33759Y274180D03*
X37830D03*
X23100Y292200D03*
Y287700D03*
X56026Y256117D03*
X23100Y283200D03*
X22750Y275450D03*
X23500Y296700D03*
X68300Y292200D03*
X45650Y250280D03*
X49320D03*
X40290Y239814D03*
X35405Y239808D03*
X32469Y250280D03*
X37469D03*
X69143Y334598D03*
X47443Y334198D03*
X27947Y334066D03*
X37049Y302949D03*
X23100Y318500D03*
Y314000D03*
X52450Y333850D03*
X31450Y334050D03*
X74150Y334250D03*
X28000Y326500D03*
X24000Y301750D03*
X23400Y309500D03*
X67800Y318000D03*
X67700Y321500D03*
X58900Y334180D03*
X62325Y334068D03*
X37900Y334380D03*
X41325Y334268D03*
X57350Y387800D03*
X46900Y378233D03*
X26100Y378352D03*
X69300Y378800D03*
X31240Y393440D03*
X49700Y391000D03*
X54040Y399390D03*
X65500Y378800D03*
X43000Y378233D03*
X22000Y378352D03*
X53500Y403150D03*
X49700Y402000D03*
X50700Y378233D03*
X54800Y373600D03*
X29900Y378252D03*
X38200Y373800D03*
X34100D03*
X73100Y378700D03*
X60400Y373600D03*
X77200Y374000D03*
X65375Y392835D03*
X35800Y363400D03*
X40100D03*
X92300Y199400D03*
Y209400D03*
Y204400D03*
X90800Y217900D03*
X82600Y232000D03*
X78850Y221000D03*
X87300Y230650D03*
X92300Y190900D03*
X81300Y178050D03*
X85700Y178000D03*
X92300Y194900D03*
X78800Y205900D03*
X92300Y213900D03*
X89800Y178000D03*
X81000Y291700D03*
X80896Y286695D03*
X80688Y281695D03*
Y276695D03*
X93884Y242333D03*
X90238Y334391D03*
X78600Y321700D03*
X78700Y317400D03*
X102300Y329100D03*
X95245Y334043D03*
X80700Y309400D03*
X80600Y304600D03*
Y334580D03*
X84025Y334468D03*
X102400Y333900D03*
X106500D03*
X89895Y378426D03*
X83232Y399956D03*
X85795Y378426D03*
X102395Y373793D03*
X93695Y378426D03*
X81300Y374000D03*
X98295Y373793D03*
X106709Y383400D03*
X112023Y383013D03*
X78171Y363195D03*
X82171D03*
X99266Y362988D03*
X103266D03*
X104900Y412200D03*
X102679Y391150D03*
X112638Y391197D03*
X107582Y391266D03*
X102850Y452650D03*
X94488Y489888D03*
X191000Y110000D03*
X182100Y105500D03*
X155991Y110061D03*
X200550Y111350D03*
X152800Y113400D03*
X164020Y101127D03*
X158612Y126645D03*
X198202Y135298D03*
X145900Y136500D03*
X196963Y122029D03*
X184600Y137400D03*
X195400Y147200D03*
X195500Y142400D03*
X201139Y121630D03*
X172800Y141001D03*
X180300Y175400D03*
X145585Y132451D03*
X197100Y298800D03*
X162522Y331774D03*
X196600Y306800D03*
X250137Y36053D03*
X242610Y53714D03*
X229000Y95000D03*
X234450Y73000D03*
X245250Y98250D03*
X261102Y77900D03*
X248169Y74454D03*
X223994Y63225D03*
X242727Y63391D03*
X261499Y55353D03*
X257499D03*
X241750Y98250D03*
X238867Y63650D03*
X255300Y72600D03*
X234693Y57400D03*
X255154Y69177D03*
X233759Y64752D03*
X220228Y63651D03*
X245800Y279200D03*
X207600Y292400D03*
X204400Y288700D03*
X248900Y282932D03*
X259629Y281000D03*
X242351Y282900D03*
X228300Y280900D03*
X219400Y279400D03*
X262800Y277835D03*
X242400Y289700D03*
X242402Y286300D03*
X225500Y278900D03*
X222320Y277658D03*
X207500Y278400D03*
X204997Y280702D03*
X253575Y320167D03*
X235500Y320100D03*
X218500Y320200D03*
X222000Y310600D03*
X231700Y320100D03*
X249775Y320167D03*
X214700Y320200D03*
X212198Y328316D03*
X208648Y328452D03*
X261365Y324351D03*
X245943Y326300D03*
X246100Y329700D03*
X230400Y326200D03*
Y329600D03*
X253245Y329698D03*
X253154Y326227D03*
X241556Y340111D03*
X237483Y339988D03*
X230000Y336500D03*
X233400Y336600D03*
X218400Y326600D03*
X218300Y330000D03*
X230400Y348000D03*
X255500Y423361D03*
X237600Y390500D03*
X261581Y370979D03*
X256172Y409530D03*
X261996Y365663D03*
X263250Y423411D03*
X257996Y365663D03*
X259800Y423400D03*
X256900Y380900D03*
X312840Y42398D03*
X325378Y50351D03*
Y35351D03*
X310065Y32397D03*
X270000Y29000D03*
Y33500D03*
Y38000D03*
Y42500D03*
X281700Y52285D03*
X285500D03*
X267188Y55192D03*
X296385Y108227D03*
X285361Y78015D03*
X281761D03*
X289161Y58068D03*
X277514D03*
X308591Y68928D03*
X304591D03*
X308591Y73074D03*
X311182Y58692D03*
X276700Y66700D03*
X283385Y100227D03*
X287385D03*
X319533Y114283D03*
X291385Y100227D03*
X295385D03*
X306196Y110209D03*
X310711Y113820D03*
X314772Y108292D03*
X300311Y60800D03*
X300385Y108227D03*
X311182Y62800D03*
X272937Y90362D03*
X266895Y100227D03*
X306280Y82574D03*
X283393Y92325D03*
X301280Y82574D03*
X272937Y85862D03*
X304591Y73074D03*
X318773Y108083D03*
X278039Y82185D03*
X279385Y100227D03*
X292030Y90574D03*
X292385Y108227D03*
X280298Y95556D03*
X296280Y82574D03*
X324026Y115936D03*
X321343Y122343D03*
X321051Y134028D03*
X304529Y118792D03*
X317700Y275400D03*
X270143Y276969D03*
X323681Y259023D03*
X319881D03*
X284498Y299976D03*
X299635Y292650D03*
X317600Y278800D03*
X319543Y290159D03*
X303032Y289900D03*
X268400Y281000D03*
X266406Y277835D03*
X306292Y252825D03*
X302262Y262642D03*
X299635Y288650D03*
X292225Y288267D03*
X297021Y346579D03*
X287350Y351200D03*
X319550Y347169D03*
X305147Y354706D03*
X316050Y342200D03*
X287350Y357700D03*
X322500Y353700D03*
X301500Y337500D03*
X320650Y336456D03*
X306060Y337640D03*
X310200Y337600D03*
X294250Y325000D03*
X277150Y332000D03*
X273165Y320351D03*
X280800Y325000D03*
X290750D03*
X280217Y350927D03*
X269365Y320351D03*
X325500Y325400D03*
X314241Y308459D03*
X314300Y311900D03*
X308180Y305200D03*
X305628Y320511D03*
X301628D03*
X325500Y321400D03*
X314400Y327851D03*
X314045Y302900D03*
X314500Y324251D03*
X319100Y330600D03*
X305628Y324511D03*
X324100Y307814D03*
X265365Y324351D03*
X281150Y332000D03*
X288536Y314764D03*
X275696Y314340D03*
X308398Y386479D03*
X304205Y382450D03*
X304398Y386479D03*
X292800Y363800D03*
X300019Y379524D03*
X296079D03*
X325200Y365100D03*
X312398Y386479D03*
X266300Y412100D03*
X270618Y385867D03*
X268004Y424361D03*
X323448Y405064D03*
X266500Y364000D03*
X325651Y439668D03*
X325629Y443510D03*
X328600Y114400D03*
X328711Y108053D03*
X335722Y94574D03*
X329722D03*
X374616Y172378D03*
X370061Y172433D03*
X355500Y144500D03*
X342000Y141600D03*
X331649Y126111D03*
X339049Y124238D03*
X335994Y126119D03*
X341913Y145049D03*
X374915Y176442D03*
X359969Y124510D03*
X349911Y136954D03*
X341757Y211056D03*
X337157Y206052D03*
X335701Y223995D03*
X352047Y220590D03*
X357546Y230354D03*
X360710Y231897D03*
X376306Y182715D03*
X351723Y178499D03*
X354143Y183439D03*
X362260Y184360D03*
X364169Y188366D03*
X366460Y191794D03*
X368558Y194540D03*
X379415Y194608D03*
X370570Y198219D03*
X371124Y178760D03*
X372517Y182362D03*
X380400Y287400D03*
X382000Y296500D03*
X384600Y285600D03*
X368714Y261134D03*
X339500Y260400D03*
X327868Y290125D03*
X365996Y287265D03*
Y272841D03*
X366169Y246591D03*
X370669D03*
X338650Y281350D03*
X361996Y272841D03*
X379000Y272600D03*
X384300Y291100D03*
X346900Y281300D03*
X343100D03*
X357996Y272841D03*
X328134Y252720D03*
X332000Y266336D03*
X376633Y261543D03*
X340280Y253765D03*
X337500Y266050D03*
X358096Y262268D03*
X341998Y256700D03*
X368610Y257299D03*
X376633Y256851D03*
X385887Y305222D03*
X381396Y302610D03*
X335400Y337400D03*
X345700Y349773D03*
X337600Y349600D03*
X339000Y344700D03*
X330000Y345800D03*
X335882Y309823D03*
X327400Y342600D03*
X386159Y337080D03*
X368050Y337200D03*
X370250Y347600D03*
X379148Y337184D03*
X384341Y315377D03*
X377324Y302844D03*
X360050Y337200D03*
X348600Y323900D03*
X359400Y347200D03*
X375148Y337184D03*
X382600Y337200D03*
X344000Y316000D03*
X346500Y302500D03*
X356550Y337200D03*
X348596Y337250D03*
X347750Y315850D03*
X352396Y337200D03*
X331026Y303354D03*
X328100Y331300D03*
X329364Y316949D03*
X364050Y337200D03*
X374250Y347600D03*
X359200Y315800D03*
X355200D03*
X360300Y323900D03*
X363400Y315800D03*
X344000Y388500D03*
X340375Y365944D03*
X331765Y386535D03*
X367450Y409955D03*
X338000Y421000D03*
X367350Y406455D03*
X360000Y410000D03*
X337592Y405027D03*
X327365Y433732D03*
X337900Y431200D03*
X399606Y202756D03*
X395669D03*
X399606Y206693D03*
X395669D03*
X391732D03*
X399606Y210630D03*
X395669D03*
X391732D03*
X399606Y316930D03*
X395669D03*
X391732D03*
X399606Y320867D03*
X395669D03*
X391732D03*
X399606Y324804D03*
X395669D03*
X448300Y337500D03*
X444100Y341000D03*
X444200Y337600D03*
X444100Y345000D03*
X440300Y337500D03*
X444959Y352053D03*
X389559Y337103D03*
X421500Y337500D03*
X427500D03*
X448431Y348737D03*
X416822Y347133D03*
X412381Y347149D03*
X435000Y347800D03*
X441000D03*
X433500Y337500D03*
X426464Y347078D03*
X397000Y337000D03*
X401700Y337350D03*
X392959Y337099D03*
X405921Y347159D03*
X430464Y347078D03*
X390550Y326820D03*
X405783Y339318D03*
X448500Y424000D03*
X445000Y422000D03*
X490877Y176547D03*
X510427Y176431D03*
X500302Y176489D03*
X509843Y202756D03*
X505906D03*
X509843Y206693D03*
X505906D03*
X509843Y210630D03*
X505906D03*
X490877Y189047D03*
Y185047D03*
Y180547D03*
X510427Y188931D03*
Y184931D03*
Y180431D03*
X500302Y188989D03*
Y184989D03*
Y180489D03*
X509843Y316930D03*
X505906D03*
X509843Y320867D03*
X505906D03*
X509843Y324804D03*
X505906D03*
X452300Y337500D03*
X468300D03*
X456550D03*
X464300D03*
X460800Y337562D03*
X460300Y333500D03*
X481359Y347727D03*
X467774Y362151D03*
X467100Y357500D03*
X464500Y347410D03*
X502138Y348500D03*
X476500Y347650D03*
X498138Y348500D03*
X506200Y358809D03*
X493200Y358800D03*
X498700Y359209D03*
X452600Y332700D03*
X462450Y358960D03*
X472463Y329837D03*
X468500Y347500D03*
X476200Y334900D03*
X506262Y348500D03*
X510138D03*
X479640Y334674D03*
X485100Y366800D03*
X490000Y363700D03*
X502850Y368500D03*
X503800Y382700D03*
X473900Y371800D03*
X485100Y363400D03*
X510200Y363209D03*
X506200D03*
X494400Y363800D03*
X499100Y363409D03*
X452500Y423500D03*
X510700Y367309D03*
X506700D03*
X489600Y367209D03*
X474200Y367500D03*
X457599Y419642D03*
X496300Y378935D03*
X489500Y371200D03*
X520552Y176373D03*
X513780Y206693D03*
Y210630D03*
X557500Y231900D03*
X553500D03*
X549000D03*
X545000D03*
X520552Y188873D03*
Y184873D03*
Y180373D03*
X554717Y255796D03*
X550717D03*
X546217D03*
X542217D03*
X554975Y248209D03*
X550975D03*
X546475D03*
X542475D03*
X555865Y240638D03*
X551865D03*
X547365D03*
X543365D03*
X513780Y316930D03*
Y320867D03*
X542627Y324049D03*
X546627D03*
X551127D03*
X555127D03*
X541278Y315738D03*
X545278D03*
X549778D03*
X553778D03*
X541221Y308771D03*
X545221D03*
X549721D03*
X553721D03*
X541193Y301280D03*
X545193D03*
X549693D03*
X553693D03*
X552200Y339300D03*
X556800D03*
X547225Y357997D03*
X547379Y338352D03*
X539900Y338300D03*
X534000Y338400D03*
X538225Y357997D03*
X555697Y356565D03*
X514000Y359209D03*
X514138Y348500D03*
X518138Y348350D03*
X525438Y350500D03*
X519263Y327092D03*
X538476Y334365D03*
X538436Y330918D03*
X534100Y342410D03*
X536200Y348300D03*
X540200D03*
X550100D03*
X546100D03*
X554685Y333410D03*
X547927Y342199D03*
X543646Y342347D03*
X539446D03*
X519629Y330448D03*
X521914Y332907D03*
X557411Y481025D03*
X554250Y457500D03*
X574250Y466900D03*
X545880Y485940D03*
X539040Y480090D03*
X562460Y457580D03*
X517125Y488975D03*
X629813Y27661D03*
X631864Y51848D03*
X632416Y31609D03*
X627603Y43523D03*
X627500Y19339D03*
X626786Y31227D03*
X635942Y97351D03*
X634400Y102000D03*
X630600D03*
X627500Y64500D03*
X629500Y61500D03*
X590537Y170119D03*
X589706Y174031D03*
X586912Y154495D03*
X586081Y158407D03*
X585145Y162809D03*
X584314Y166721D03*
X596233Y145667D03*
X595402Y149579D03*
X594466Y153981D03*
X593635Y157893D03*
X588901Y134308D03*
X588070Y138220D03*
X587134Y142622D03*
X586303Y146534D03*
X577699Y123469D03*
X576868Y127381D03*
X575932Y131783D03*
X575101Y135695D03*
X634169Y166500D03*
X618250Y162081D03*
X618400Y173443D03*
X617600Y134400D03*
X635852Y133715D03*
X589966Y210195D03*
X589135Y214107D03*
X588199Y218509D03*
X587368Y222421D03*
X585841Y194571D03*
X585010Y198483D03*
X584074Y202885D03*
X583243Y206797D03*
X581716Y178947D03*
X580885Y182859D03*
X579949Y187261D03*
X579118Y191173D03*
X588770Y178433D03*
X587939Y182345D03*
X627455Y185364D03*
X634000Y234200D03*
X630000D03*
X636363Y209944D03*
X632363D03*
X628363D03*
X624363D03*
X622400Y216750D03*
X598600Y247800D03*
Y253100D03*
X633800Y239600D03*
X629900Y239700D03*
X633800Y245700D03*
X629900Y245800D03*
X634100Y252000D03*
X629900D03*
X594025Y284017D03*
X618300Y288745D03*
X632750Y292195D03*
Y295641D03*
X594025Y280017D03*
X590050Y337950D03*
X590200Y334350D03*
X610750Y336850D03*
X594050Y301755D03*
X632750Y330854D03*
Y334300D03*
X618300Y327654D03*
X632900Y344950D03*
X612300Y356850D03*
X608500Y315000D03*
X634000Y306300D03*
X631800Y316137D03*
X603650Y315500D03*
X594292Y362291D03*
X625000Y361700D03*
X590350Y323011D03*
X629250Y310491D03*
Y306491D03*
X626405Y314991D03*
X629250Y344900D03*
Y348900D03*
X623063Y357337D03*
X602649Y349033D03*
X594400Y357000D03*
Y353000D03*
X597450Y324750D03*
Y320750D03*
X627020Y393364D03*
X598152Y370130D03*
X629770Y369320D03*
X594200Y390400D03*
X629400Y414324D03*
X584280Y424030D03*
X598023Y383081D03*
X624200Y372500D03*
X620260Y389940D03*
X589394Y384572D03*
X589391Y378202D03*
X627140Y381353D03*
X631140D03*
X594200Y395200D03*
X604832Y395220D03*
X630000Y464900D03*
X626300D03*
X577330Y464430D03*
X599900Y438300D03*
X587890Y426720D03*
X581020Y471890D03*
X574667Y479799D03*
X577300Y460300D03*
X588400Y469450D03*
X634050Y469200D03*
X588663Y460037D03*
X581250Y480550D03*
X585420Y456480D03*
X633676Y460080D03*
X617000Y468700D03*
X588030Y430795D03*
X620600Y458500D03*
X652551Y40716D03*
X656450Y28000D03*
X655914Y39932D03*
X667149Y23411D03*
X656300Y20100D03*
X660200Y20200D03*
X647216Y31601D03*
X667900Y40800D03*
X643816Y31573D03*
X640144Y40969D03*
X643103Y13803D03*
X664301Y40104D03*
Y49998D03*
X638103Y13100D03*
X640416Y31609D03*
X647103Y13964D03*
X694365Y98458D03*
Y94458D03*
Y90958D03*
Y86958D03*
X686279Y98494D03*
Y94494D03*
Y90994D03*
Y86994D03*
X678225Y98496D03*
Y94496D03*
Y90996D03*
Y86996D03*
X670146Y98505D03*
Y94505D03*
Y91005D03*
Y87005D03*
X662047Y98539D03*
Y94539D03*
Y91039D03*
Y87039D03*
X654037Y98708D03*
Y94708D03*
Y91208D03*
Y87208D03*
X637003Y68809D03*
X648207Y70750D03*
X654330Y113385D03*
X688976D03*
X646643Y97859D03*
X644100Y111811D03*
X668100Y56100D03*
X651564Y52638D03*
X644500Y65759D03*
X657480Y113385D03*
X678189Y108784D03*
X689049Y109487D03*
X669500Y108400D03*
X640600Y111600D03*
X641003Y68809D03*
X654330Y154330D03*
X657480Y151219D03*
X663778Y166928D03*
X673227Y157479D03*
X673229Y166929D03*
Y173228D03*
X670080Y148030D03*
X679526Y144880D03*
X660629Y138584D03*
Y141732D03*
X688978Y135435D03*
X682679D03*
X676379D03*
X695274Y135431D03*
X698425Y129134D03*
X663778Y160629D03*
Y154330D03*
Y135431D03*
X692124D03*
X673227Y144880D03*
X685825Y138581D03*
X679526D03*
X673227D03*
X666928D03*
X648032Y129134D03*
X657480Y122834D03*
X698425Y135433D03*
Y138582D03*
X692125D03*
X682677Y148031D03*
X688976D03*
X695275D03*
X682677Y154330D03*
X688976D03*
X695275D03*
Y160629D03*
X688976D03*
X682677Y160630D03*
X679527Y163779D03*
X695275Y166929D03*
X688976D03*
X682677D03*
X695275Y173228D03*
X688976D03*
X682677D03*
X654330Y170078D03*
X648031Y163779D03*
X654330D03*
X651181Y157480D03*
X670078Y154330D03*
X644882Y157480D03*
X666929Y125984D03*
X657480Y129134D03*
X651181Y151181D03*
X698425Y116535D03*
X648059Y151191D03*
X685827Y125985D03*
X676377Y116536D03*
X663778Y176377D03*
Y173227D03*
Y170078D03*
X670078Y166928D03*
Y173227D03*
X654330Y176377D03*
X639108Y167800D03*
X648057Y141721D03*
X648032Y135434D03*
Y122835D03*
X660629Y116536D03*
X666929Y116535D03*
X698426Y122835D03*
X692148Y129119D03*
X670116Y132283D03*
X673229Y125985D03*
X679528D03*
X660629Y170078D03*
Y173227D03*
X654330Y157480D03*
X651181Y154330D03*
X673229Y170079D03*
X679527Y173229D03*
X692126Y141732D03*
X698425D03*
X679527Y148031D03*
X685826D03*
X692126D03*
X698425D03*
X679527Y154330D03*
X685826D03*
X692126D03*
X698425D03*
Y160629D03*
X692126D03*
X685826D03*
X679527D03*
X698425Y166929D03*
X692126D03*
X685826D03*
X679527D03*
X698425Y173228D03*
X692126D03*
X685826D03*
X670078Y170078D03*
X654330Y173228D03*
X651181Y166929D03*
X676376Y132281D03*
X666929Y129134D03*
X660630Y160630D03*
X640775Y156218D03*
X648031Y157480D03*
X663779Y151181D03*
X666929Y148031D03*
X663779Y132283D03*
X663778Y144883D03*
Y138584D03*
X651181Y141732D03*
Y132283D03*
Y122834D03*
X644882Y154331D03*
X637952Y142515D03*
X640500Y125000D03*
X660629Y144883D03*
X657481Y132284D03*
X670078Y151181D03*
X637343Y171335D03*
Y174835D03*
X657480Y154330D03*
X644882Y173228D03*
Y176378D03*
Y170078D03*
X648031D03*
X670078Y157480D03*
X673228Y148031D03*
X692126Y125984D03*
X685827Y116535D03*
X670079Y125985D03*
X682678D03*
X676378D03*
X688977D03*
X676378Y119686D03*
X666929Y119685D03*
X663780Y125985D03*
X657479Y116536D03*
X654330Y116535D03*
Y119685D03*
Y122834D03*
X657480Y125984D03*
X654331D03*
X654330Y129134D03*
Y132283D03*
Y135433D03*
X651181D03*
X654330Y138582D03*
Y141732D03*
Y144882D03*
X651181D03*
X654330Y148031D03*
Y151181D03*
X679452Y209815D03*
X651181Y188976D03*
X679527Y182679D03*
Y188975D03*
X676379Y182678D03*
X692126Y182676D03*
Y185827D03*
Y179527D03*
X676379Y192126D03*
X670080Y182678D03*
X697069Y207157D03*
X663400Y234100D03*
X663200Y238100D03*
X682676Y179526D03*
Y188975D03*
X682677Y182677D03*
X682676Y185826D03*
X676377Y201574D03*
Y204723D03*
X685826Y198424D03*
X663778Y182676D03*
Y179526D03*
X654330Y182676D03*
X660629Y192125D03*
X666929D03*
X660630Y198425D03*
X676377Y198424D03*
X685826Y201574D03*
X682677Y192125D03*
X688976D03*
X698425D03*
X640931Y181102D03*
X646594Y210875D03*
X640584Y194127D03*
X683913Y213313D03*
X695275Y198425D03*
X692125Y198423D03*
X686352Y207200D03*
X651181Y192125D03*
X663779D03*
X657480D03*
X670078D03*
X654330Y185826D03*
Y179526D03*
X685826Y192125D03*
X692125D03*
X667353Y233486D03*
X640363Y209944D03*
X638479Y230640D03*
X674023Y213815D03*
X640509Y177600D03*
X674172Y210095D03*
X679400Y213300D03*
X679527Y198424D03*
X697149Y219742D03*
X692949D03*
X695600Y240354D03*
X682700D03*
X695625Y282250D03*
X669125Y280405D03*
X663000Y249200D03*
X663100Y252700D03*
X674841Y262854D03*
X695383Y266855D03*
X644153Y278745D03*
X660400Y271900D03*
X678500Y240324D03*
X691100Y240354D03*
X686900D03*
X668600Y242800D03*
X669450Y284900D03*
X695600Y244354D03*
X695375Y260875D03*
X637500Y362400D03*
X680300Y384900D03*
X662306Y365477D03*
X657673Y365400D03*
X672281Y378883D03*
X693500Y373300D03*
X694765Y406915D03*
X685750Y419460D03*
X642900Y395400D03*
X674150Y415380D03*
X654770Y401166D03*
X645970Y399130D03*
X669031Y388383D03*
X665031D03*
X653360Y386210D03*
X680700Y378200D03*
X687150Y385550D03*
X675031Y389383D03*
X653007Y382828D03*
X658601Y401800D03*
X673900Y418880D03*
X637500Y365900D03*
X672800Y438832D03*
X696950Y441400D03*
X667414Y431956D03*
X692200Y428700D03*
X681540Y429640D03*
X678700Y440950D03*
X671640Y454410D03*
X683250Y437813D03*
X710378Y100399D03*
Y96399D03*
Y92899D03*
Y88899D03*
X702391Y98510D03*
Y94510D03*
Y91010D03*
Y87010D03*
X728788Y88540D03*
X725295Y88609D03*
X752853Y100900D03*
X722673Y105444D03*
X736785Y110185D03*
X737800Y106525D03*
X717197Y109646D03*
X726100Y107200D03*
X734709Y106595D03*
X731000Y106315D03*
X734212Y109995D03*
X725943Y100147D03*
X744833Y78995D03*
X754572Y86923D03*
X754528Y83228D03*
X745100Y97500D03*
X699563Y108815D03*
X719010Y107281D03*
X707649Y110002D03*
X710517Y106823D03*
X750773Y74636D03*
X747919Y76667D03*
X720744Y92427D03*
X704849Y107385D03*
X733069Y166930D03*
X704725Y135434D03*
X707874Y141732D03*
X701574Y138582D03*
X701575Y135433D03*
X711023Y132283D03*
X704724D03*
X717322Y129133D03*
X726770Y166930D03*
Y173229D03*
X701574Y148031D03*
X707873D03*
X701574Y154330D03*
X707873D03*
Y160629D03*
X701574D03*
X707873Y166929D03*
X701574D03*
X707873Y173228D03*
X701574D03*
X711023Y122834D03*
X717322D03*
X723622D03*
X711023Y141732D03*
X743452Y151815D03*
X714172Y173227D03*
Y144880D03*
Y151180D03*
X717322Y144880D03*
Y151180D03*
X714172Y163778D03*
Y157479D03*
X717322Y163778D03*
Y157479D03*
Y166928D03*
X720472Y173228D03*
Y148031D03*
Y141732D03*
Y160629D03*
Y154330D03*
X720471Y166928D03*
X717322Y141731D03*
X758050Y164050D03*
X704725Y122835D03*
X720472Y135433D03*
X729921Y157480D03*
X739952Y120649D03*
X740952Y126815D03*
X707874Y116535D03*
X743100Y114700D03*
X737352Y145885D03*
X726771Y122835D03*
X729921Y122834D03*
X737702Y128565D03*
X729921Y132283D03*
Y129134D03*
X711023Y116535D03*
X726771Y163779D03*
X741754Y134617D03*
X729921Y135433D03*
X739622Y137008D03*
X729921Y138582D03*
Y144882D03*
X714173Y116535D03*
X717322D03*
X707873Y129133D03*
X720473Y116536D03*
X704725D03*
X704724Y148031D03*
Y154330D03*
Y160629D03*
Y166929D03*
Y173228D03*
X714173Y122834D03*
X720472D03*
X741077Y159790D03*
X757471Y148193D03*
X723621Y148031D03*
Y154330D03*
Y160629D03*
Y166929D03*
Y173228D03*
X707874Y122835D03*
X723621Y135433D03*
Y129133D03*
Y141732D03*
X701575Y122835D03*
X714173Y141732D03*
X723622Y116535D03*
X704723Y129133D03*
X701574D03*
X711022D03*
X714172D03*
X729921Y125984D03*
X711023Y173228D03*
X741952Y173115D03*
X738352Y174615D03*
X729920Y176378D03*
Y173229D03*
X736219Y170079D03*
X733070D03*
X746750Y157700D03*
X729921Y148031D03*
Y141732D03*
Y163779D03*
X750550Y135200D03*
X729921Y160629D03*
X701575Y116536D03*
X729921Y154330D03*
X717322Y182676D03*
X711024Y188976D03*
X701575Y182676D03*
X711022Y185825D03*
X701575Y185827D03*
Y179527D03*
X726770Y179528D03*
Y185827D03*
X743200Y227900D03*
X726770Y192126D03*
X730694Y224473D03*
X726656Y235244D03*
X711022Y179526D03*
X714172D03*
X722523Y221315D03*
X720437Y185829D03*
X720472Y179527D03*
Y192125D03*
X711022Y182676D03*
X704724Y192125D03*
X711024D03*
X730737Y235199D03*
X724465Y224741D03*
X714620Y221041D03*
X743460Y231900D03*
X701574Y192125D03*
X707873D03*
X714173D03*
X723621D03*
Y185826D03*
Y179527D03*
X715467Y210507D03*
X725009Y213292D03*
X739852Y195915D03*
X737832Y202664D03*
X729920Y188977D03*
X739752Y199615D03*
X738416Y190551D03*
X729920Y182678D03*
X745485Y197673D03*
Y201673D03*
X740352Y180115D03*
X729920Y185827D03*
X724776Y209963D03*
X743752Y187115D03*
X742502Y182715D03*
X742252Y177015D03*
X737315Y177952D03*
X733070Y179527D03*
X720819Y209800D03*
X729246Y209941D03*
X736272Y208181D03*
X729136Y206654D03*
X738839Y206080D03*
X733565Y210184D03*
X729920Y192126D03*
X720357Y207104D03*
X714173Y198425D03*
X729921Y179527D03*
X720471Y198424D03*
X731915Y206310D03*
X738952Y184215D03*
X744052Y193784D03*
X701574Y198424D03*
X711023Y198425D03*
X704724D03*
X717322D03*
X707873Y198424D03*
X723621D03*
X704724Y201574D03*
X706737Y205505D03*
X705336Y208437D03*
X711310Y207023D03*
X714173Y201574D03*
X718330Y205172D03*
X704708Y264647D03*
X751878Y276817D03*
X749620Y273620D03*
X707574Y276558D03*
X712720Y240976D03*
X754227Y297611D03*
X739300Y287611D03*
X751693Y255540D03*
X743507Y251685D03*
X747558Y247274D03*
X759558Y241027D03*
Y247274D03*
X731300Y287611D03*
X735300D03*
X731318Y283571D03*
X735318D03*
X731155Y279636D03*
X739318Y283571D03*
X734638Y275696D03*
X751693Y259540D03*
X755693D03*
X704708Y256647D03*
Y252647D03*
X753560Y273780D03*
X704708Y260647D03*
X751133Y313984D03*
X754227Y301111D03*
X705320Y420610D03*
X735570Y424760D03*
X721380Y423930D03*
X739680Y423900D03*
X700200Y388200D03*
Y384800D03*
X718110Y442960D03*
X708355Y454712D03*
X701120Y430620D03*
X719920Y429700D03*
X743480Y439080D03*
X710200Y441200D03*
X706120Y441410D03*
X729870Y451300D03*
X740900Y456400D03*
X700855Y426719D03*
X799250Y71125D03*
X772107Y83046D03*
X799493Y93250D03*
X761650Y89937D03*
X771610Y93040D03*
X799500Y106000D03*
X781000Y88000D03*
Y84200D03*
X788287Y86087D03*
X768250Y106300D03*
X768100Y109700D03*
X763560Y59820D03*
X767359Y82076D03*
X782500Y134283D03*
X773000Y119600D03*
X776600D03*
X794500Y134283D03*
X785000Y158900D03*
X760600Y173700D03*
X804320Y134300D03*
X804400Y175000D03*
X760800Y169550D03*
X769600Y164200D03*
X765200Y135750D03*
X786500Y134283D03*
X763050Y154100D03*
X761400Y160050D03*
X764600Y141500D03*
X768700Y129800D03*
X768900Y134800D03*
X760715Y210200D03*
X804412Y185332D03*
X800612Y185432D03*
X760715Y201700D03*
Y214200D03*
X790000Y224700D03*
X760715Y197200D03*
X764550Y182900D03*
X764750Y179300D03*
X761550Y180500D03*
X786400Y179000D03*
X779200Y178650D03*
X790714Y237308D03*
X801618Y210116D03*
Y214116D03*
X795498Y246171D03*
X793912Y297020D03*
X793837Y283696D03*
X781640Y278660D03*
X786006Y283383D03*
X775486Y287316D03*
X781640Y282160D03*
X793837Y291696D03*
X805254Y263886D03*
X761484Y255581D03*
Y251581D03*
X780837Y240885D03*
X774637Y267746D03*
X770637D03*
X761638Y259635D03*
X774637Y259746D03*
Y263746D03*
X793837Y279636D03*
Y275696D03*
X780837Y267826D03*
X784837Y263891D03*
Y259951D03*
X793852Y256011D03*
Y252076D03*
X793837Y271761D03*
Y267826D03*
Y263696D03*
X774657Y255999D03*
X765638Y255635D03*
X774637Y251876D03*
X784837Y271761D03*
Y267826D03*
X793837Y287696D03*
X780837Y271761D03*
X801853Y300515D03*
X767890Y273380D03*
X763292Y287630D03*
X786610Y321340D03*
X786300Y309900D03*
X761520Y339110D03*
X765764Y326844D03*
X801728Y304572D03*
X776497Y338392D03*
X775672Y350204D03*
X782770Y321200D03*
G54D125*
G01X121778Y-377522D02*
X122652Y-376647D01*
X123307Y-375189D01*
X123744Y-373146D01*
X123307Y-371397D01*
X122434Y-370230D01*
X120905Y-369355D01*
X115010D01*
Y-386855D01*
X122215D01*
X123744Y-385689D01*
X124617Y-383938D01*
X125054Y-381897D01*
X124617Y-379855D01*
X123307Y-378105D01*
X121778Y-377522D01*
X115010D01*
G01X134475Y-386855D02*
Y-375189D01*
G01Y-377522D02*
X135567Y-376355D01*
X136659Y-375480D01*
X138187Y-375189D01*
X139278Y-375480D01*
X140589Y-376355D01*
G01X150447Y-392105D02*
X151757Y-392688D01*
X153504Y-392105D01*
X154595Y-390939D01*
X155469Y-389480D01*
X156778Y-384814D01*
X159617Y-375189D01*
G01X152630D02*
X156778Y-384814D01*
G01X176025Y-376647D02*
X174497Y-375480D01*
X173187Y-375189D01*
X171440Y-375772D01*
X170130Y-376938D01*
X169257Y-378980D01*
X169038Y-381022D01*
X169257Y-383064D01*
X170130Y-384814D01*
X171440Y-386272D01*
X173187Y-386855D01*
X174715Y-386272D01*
X176025Y-385105D01*
G01X186757Y-378980D02*
X193744D01*
X193089Y-376938D01*
X191997Y-375772D01*
X190469Y-375189D01*
X188940Y-375480D01*
X187630Y-376355D01*
X186757Y-378397D01*
X186320Y-380147D01*
Y-381897D01*
X186757Y-383647D01*
X187849Y-385397D01*
X189159Y-386563D01*
X190687Y-386855D01*
X192215Y-386272D01*
X193744Y-384522D01*
G01X229835Y-370814D02*
X228525Y-369938D01*
X226997Y-369355D01*
X225250D01*
X223285Y-370230D01*
X221757Y-371688D01*
X220665Y-373439D01*
X219792Y-376355D01*
X219573Y-378980D01*
X220010Y-381605D01*
X220665Y-383355D01*
X221975Y-385105D01*
X223504Y-386272D01*
X225032Y-386855D01*
X226560D01*
X228089Y-386272D01*
X229399Y-385397D01*
X230491Y-384231D01*
G01X246462Y-386855D02*
Y-375189D01*
G01Y-377230D02*
X245589Y-376064D01*
X244278Y-375480D01*
X242750Y-375189D01*
X241222Y-375772D01*
X239912Y-376938D01*
X239038Y-378688D01*
X238602Y-381022D01*
X239038Y-383355D01*
X239912Y-385105D01*
X241222Y-386272D01*
X242750Y-386855D01*
X244278Y-386563D01*
X245589Y-385689D01*
X246462Y-384522D01*
G01X256320Y-386855D02*
Y-375189D01*
G01Y-378105D02*
X257194Y-376647D01*
X258504Y-375480D01*
X260250Y-375189D01*
X261778Y-375480D01*
X263089Y-376647D01*
X263744Y-378688D01*
Y-386855D01*
G01X272947Y-392105D02*
X274257Y-392688D01*
X276004Y-392105D01*
X277095Y-390939D01*
X277969Y-389480D01*
X279278Y-384814D01*
X282117Y-375189D01*
G01X275130D02*
X279278Y-384814D01*
G01X295032Y-386855D02*
X293722Y-386563D01*
X292412Y-385397D01*
X291538Y-383355D01*
X291102Y-381022D01*
X291538Y-378688D01*
X292412Y-376647D01*
X293722Y-375480D01*
X295032Y-375189D01*
X296342Y-375480D01*
X297652Y-376647D01*
X298525Y-378688D01*
X298744Y-381022D01*
X298525Y-383355D01*
X297652Y-385397D01*
X296342Y-386563D01*
X295032Y-386855D01*
G01X308820D02*
Y-375189D01*
G01Y-378105D02*
X309694Y-376647D01*
X311004Y-375480D01*
X312750Y-375189D01*
X314278Y-375480D01*
X315589Y-376647D01*
X316244Y-378688D01*
Y-386855D01*
G01X342947Y-384522D02*
X344694Y-385980D01*
X346659Y-386855D01*
X348405D01*
X350152Y-385980D01*
X351462Y-384522D01*
X352117Y-382480D01*
X351680Y-380439D01*
X350589Y-378688D01*
X348624Y-377522D01*
X346004Y-376938D01*
X344475Y-375772D01*
X343820Y-373730D01*
X344257Y-371688D01*
X345349Y-370230D01*
X346877Y-369355D01*
X348405D01*
X349934Y-369938D01*
X351244Y-371397D01*
G01X369835Y-370814D02*
X368525Y-369938D01*
X366997Y-369355D01*
X365250D01*
X363285Y-370230D01*
X361757Y-371688D01*
X360665Y-373439D01*
X359792Y-376355D01*
X359573Y-378980D01*
X360010Y-381605D01*
X360665Y-383355D01*
X361975Y-385105D01*
X363504Y-386272D01*
X365032Y-386855D01*
X366560D01*
X368089Y-386272D01*
X369399Y-385397D01*
X370491Y-384231D01*
G01X387335Y-370814D02*
X386025Y-369938D01*
X384497Y-369355D01*
X382750D01*
X380785Y-370230D01*
X379257Y-371688D01*
X378165Y-373439D01*
X377292Y-376355D01*
X377073Y-378980D01*
X377510Y-381605D01*
X378165Y-383355D01*
X379475Y-385105D01*
X381004Y-386272D01*
X382532Y-386855D01*
X384060D01*
X385589Y-386272D01*
X386899Y-385397D01*
X387991Y-384231D01*
G01X210605Y-341855D02*
Y-324355D01*
X216282Y-338938D01*
X221959Y-324355D01*
Y-341855D01*
G01X233782D02*
X232472Y-341563D01*
X231162Y-340397D01*
X230288Y-338355D01*
X229852Y-336022D01*
X230288Y-333688D01*
X231162Y-331647D01*
X232472Y-330480D01*
X233782Y-330189D01*
X235092Y-330480D01*
X236402Y-331647D01*
X237275Y-333688D01*
X237494Y-336022D01*
X237275Y-338355D01*
X236402Y-340397D01*
X235092Y-341563D01*
X233782Y-341855D01*
G01X255212Y-324355D02*
Y-341855D01*
G01Y-339231D02*
X254339Y-340689D01*
X253028Y-341563D01*
X251500Y-341855D01*
X249754Y-341272D01*
X248444Y-339814D01*
X247570Y-338064D01*
X247352Y-336022D01*
X247570Y-333980D01*
X248444Y-332230D01*
X249754Y-330772D01*
X251500Y-330189D01*
X253028Y-330480D01*
X254120Y-331064D01*
X255212Y-332230D01*
G01X265507Y-333980D02*
X272494D01*
X271839Y-331938D01*
X270747Y-330772D01*
X269219Y-330189D01*
X267690Y-330480D01*
X266380Y-331355D01*
X265507Y-333397D01*
X265070Y-335147D01*
Y-336897D01*
X265507Y-338647D01*
X266599Y-340397D01*
X267909Y-341563D01*
X269437Y-341855D01*
X270965Y-341272D01*
X272494Y-339522D01*
G01X286282Y-341855D02*
Y-324355D01*
G01X566882Y-386855D02*
Y-369355D01*
X564262Y-372855D01*
G01Y-386855D02*
X569502D01*
G01X580234Y-379564D02*
X581762Y-377522D01*
X583072Y-376355D01*
X584819Y-375772D01*
X586347Y-376355D01*
X587439Y-377522D01*
X588312Y-379272D01*
X588530Y-381313D01*
X588312Y-383064D01*
X587439Y-384814D01*
X586128Y-386272D01*
X584600Y-386855D01*
X582854Y-386272D01*
X581325Y-384522D01*
X580452Y-381897D01*
X580234Y-378980D01*
X580670Y-375189D01*
X581325Y-373146D01*
X582417Y-371105D01*
X583945Y-369647D01*
X585474Y-369355D01*
X587002Y-369938D01*
X588094Y-371397D01*
G01X597079Y-383355D02*
X598388Y-385397D01*
X600135Y-386563D01*
X602100Y-386855D01*
X603847Y-386563D01*
X605594Y-385105D01*
X606685Y-383355D01*
X606904Y-381605D01*
X606467Y-379564D01*
X604939Y-378105D01*
X603410Y-377522D01*
X601445D01*
G01X603410D02*
X604720Y-376647D01*
X605812Y-375189D01*
X606249Y-373439D01*
X605812Y-371688D01*
X604720Y-370230D01*
X602755Y-369355D01*
X600790Y-369647D01*
X598825Y-370814D01*
G01X619382Y-386855D02*
Y-369355D01*
X616762Y-372855D01*
G01Y-386855D02*
X622002D01*
G01X632734Y-379564D02*
X634262Y-377522D01*
X635572Y-376355D01*
X637319Y-375772D01*
X638847Y-376355D01*
X639939Y-377522D01*
X640812Y-379272D01*
X641030Y-381313D01*
X640812Y-383064D01*
X639939Y-384814D01*
X638628Y-386272D01*
X637100Y-386855D01*
X635354Y-386272D01*
X633825Y-384522D01*
X632952Y-381897D01*
X632734Y-378980D01*
X633170Y-375189D01*
X633825Y-373146D01*
X634917Y-371105D01*
X636445Y-369647D01*
X637974Y-369355D01*
X639502Y-369938D01*
X640594Y-371397D01*
G01X553765Y-341855D02*
Y-324355D01*
X559005D01*
X560752Y-325230D01*
X562062Y-327272D01*
X562499Y-329605D01*
X562062Y-331938D01*
X560970Y-333688D01*
X559005Y-334564D01*
X553765D01*
G01X580435Y-325814D02*
X579125Y-324938D01*
X577597Y-324355D01*
X575850D01*
X573885Y-325230D01*
X572357Y-326688D01*
X571265Y-328439D01*
X570392Y-331355D01*
X570173Y-333980D01*
X570610Y-336605D01*
X571265Y-338355D01*
X572575Y-340105D01*
X574104Y-341272D01*
X575632Y-341855D01*
X577160D01*
X578689Y-341272D01*
X579999Y-340397D01*
X581091Y-339231D01*
G01X594878Y-332522D02*
X595752Y-331647D01*
X596407Y-330189D01*
X596844Y-328146D01*
X596407Y-326397D01*
X595534Y-325230D01*
X594005Y-324355D01*
X588110D01*
Y-341855D01*
X595315D01*
X596844Y-340689D01*
X597717Y-338938D01*
X598154Y-336897D01*
X597717Y-334855D01*
X596407Y-333105D01*
X594878Y-332522D01*
X588110D01*
G01X604082Y-347688D02*
X617182D01*
G01X623110Y-341855D02*
Y-324355D01*
X633154Y-341855D01*
Y-324355D01*
G01X645632Y-341855D02*
X643885Y-341563D01*
X642357Y-340397D01*
X641047Y-338647D01*
X640173Y-336605D01*
X639737Y-334272D01*
Y-331938D01*
X640173Y-329605D01*
X641047Y-327563D01*
X642357Y-325814D01*
X643885Y-324647D01*
X645632Y-324355D01*
X647378Y-324647D01*
X648907Y-325814D01*
X650217Y-327563D01*
X651091Y-329605D01*
X651527Y-331938D01*
Y-334272D01*
X651091Y-336605D01*
X650217Y-338647D01*
X648907Y-340397D01*
X647378Y-341563D01*
X645632Y-341855D01*
G01X696473Y-324355D02*
X701932Y-341855D01*
X707391Y-324355D01*
G01X723799Y-341855D02*
X715065D01*
Y-324355D01*
X723799D01*
G01X720305Y-332813D02*
X715065D01*
G01X732565Y-341855D02*
Y-324355D01*
X738024D01*
X739770Y-325230D01*
X740862Y-326397D01*
X741299Y-328730D01*
X740862Y-331064D01*
X739552Y-332522D01*
X738024Y-333397D01*
X732565D01*
G01X738024D02*
X741299Y-341855D01*
G01X754432Y-342438D02*
X753995Y-342147D01*
Y-341563D01*
X754432Y-341272D01*
X754869Y-341563D01*
Y-342147D01*
X754432Y-342438D01*
G01X728182Y-386855D02*
Y-369355D01*
X725562Y-372855D01*
G01Y-386855D02*
X730802D01*
G01X856265Y-369355D02*
Y-386855D01*
X864999D01*
G01X878132D02*
Y-369355D01*
X875512Y-372855D01*
G01Y-386855D02*
X880752D01*
G01X830015Y-324355D02*
Y-341855D01*
X838749D01*
G01X855812D02*
Y-330189D01*
G01Y-332230D02*
X854939Y-331064D01*
X853628Y-330480D01*
X852100Y-330189D01*
X850572Y-330772D01*
X849262Y-331938D01*
X848388Y-333688D01*
X847952Y-336022D01*
X848388Y-338355D01*
X849262Y-340105D01*
X850572Y-341272D01*
X852100Y-341855D01*
X853628Y-341563D01*
X854939Y-340689D01*
X855812Y-339522D01*
G01X864797Y-347105D02*
X866107Y-347688D01*
X867854Y-347105D01*
X868945Y-345939D01*
X869819Y-344480D01*
X871128Y-339814D01*
X873967Y-330189D01*
G01X866980D02*
X871128Y-339814D01*
G01X883607Y-333980D02*
X890594D01*
X889939Y-331938D01*
X888847Y-330772D01*
X887319Y-330189D01*
X885790Y-330480D01*
X884480Y-331355D01*
X883607Y-333397D01*
X883170Y-335147D01*
Y-336897D01*
X883607Y-338647D01*
X884699Y-340397D01*
X886009Y-341563D01*
X887537Y-341855D01*
X889065Y-341272D01*
X890594Y-339522D01*
G01X901325Y-341855D02*
Y-330189D01*
G01Y-332522D02*
X902417Y-331355D01*
X903509Y-330480D01*
X905037Y-330189D01*
X906128Y-330480D01*
X907439Y-331355D01*
G01X994432Y-386855D02*
X992685Y-386563D01*
X991157Y-385397D01*
X989847Y-383647D01*
X988973Y-381605D01*
X988537Y-379272D01*
Y-376938D01*
X988973Y-374605D01*
X989847Y-372563D01*
X991157Y-370814D01*
X992685Y-369647D01*
X994432Y-369355D01*
X996178Y-369647D01*
X997707Y-370814D01*
X999017Y-372563D01*
X999891Y-374605D01*
X1000327Y-376938D01*
Y-379272D01*
X999891Y-381605D01*
X999017Y-383647D01*
X997707Y-385397D01*
X996178Y-386563D01*
X994432Y-386855D01*
G01X996178Y-382188D02*
X998799Y-386855D01*
G01X1007129Y-369355D02*
Y-381897D01*
X1008002Y-384522D01*
X1009749Y-386272D01*
X1011932Y-386855D01*
X1014115Y-386272D01*
X1015862Y-384522D01*
X1016735Y-381897D01*
Y-369355D01*
G01X1026812D02*
X1032052D01*
G01X1029432D02*
Y-386855D01*
G01X1026812D02*
X1032052D01*
G01X1041910D02*
Y-369355D01*
X1051954Y-386855D01*
Y-369355D01*
G01X1069235Y-370814D02*
X1067925Y-369938D01*
X1066397Y-369355D01*
X1064650D01*
X1062685Y-370230D01*
X1061157Y-371688D01*
X1060065Y-373439D01*
X1059192Y-376355D01*
X1058973Y-378980D01*
X1059410Y-381605D01*
X1060065Y-383355D01*
X1061375Y-385105D01*
X1062904Y-386272D01*
X1064432Y-386855D01*
X1065960D01*
X1067489Y-386272D01*
X1068799Y-385397D01*
X1069891Y-384231D01*
G01X1081932Y-386855D02*
Y-378980D01*
X1077565Y-369355D01*
G01X1086299D02*
X1081932Y-378980D01*
G01X972129Y-341855D02*
Y-324355D01*
X976495D01*
X978242Y-325230D01*
X979552Y-326397D01*
X980644Y-328146D01*
X981517Y-330189D01*
X981735Y-333105D01*
X981517Y-336022D01*
X980644Y-338064D01*
X979552Y-339814D01*
X978242Y-340980D01*
X976495Y-341855D01*
X972129D01*
G01X991157Y-333980D02*
X998144D01*
X997489Y-331938D01*
X996397Y-330772D01*
X994869Y-330189D01*
X993340Y-330480D01*
X992030Y-331355D01*
X991157Y-333397D01*
X990720Y-335147D01*
Y-336897D01*
X991157Y-338647D01*
X992249Y-340397D01*
X993559Y-341563D01*
X995087Y-341855D01*
X996615Y-341272D01*
X998144Y-339522D01*
G01X1008657Y-339814D02*
X1009749Y-340980D01*
X1011277Y-341855D01*
X1012587D01*
X1013897Y-341272D01*
X1014770Y-340397D01*
X1015207Y-339231D01*
X1014989Y-337480D01*
X1014115Y-336605D01*
X1010185Y-334855D01*
X1009312Y-332813D01*
X1009749Y-331355D01*
X1010622Y-330480D01*
X1011932Y-330189D01*
X1013242Y-330480D01*
X1014552Y-331355D01*
G01X1029432Y-330189D02*
Y-341855D01*
G01Y-325522D02*
X1028995Y-325230D01*
Y-324647D01*
X1029432Y-324355D01*
X1029869Y-324647D01*
Y-325230D01*
X1029432Y-325522D01*
G01X1043875Y-346230D02*
X1045404Y-347397D01*
X1047150Y-347688D01*
X1048678Y-347397D01*
X1049989Y-345939D01*
X1050862Y-343897D01*
Y-330189D01*
G01Y-332522D02*
X1049989Y-331355D01*
X1048678Y-330480D01*
X1047150Y-330189D01*
X1045404Y-330772D01*
X1044312Y-331938D01*
X1043438Y-333980D01*
X1043002Y-336022D01*
X1043220Y-337772D01*
X1044094Y-339814D01*
X1045404Y-341272D01*
X1047150Y-341855D01*
X1048460Y-341563D01*
X1049989Y-340397D01*
X1050862Y-339231D01*
G01X1060720Y-341855D02*
Y-330189D01*
G01Y-333105D02*
X1061594Y-331647D01*
X1062904Y-330480D01*
X1064650Y-330189D01*
X1066178Y-330480D01*
X1067489Y-331647D01*
X1068144Y-333688D01*
Y-341855D01*
G01X1078657Y-333980D02*
X1085644D01*
X1084989Y-331938D01*
X1083897Y-330772D01*
X1082369Y-330189D01*
X1080840Y-330480D01*
X1079530Y-331355D01*
X1078657Y-333397D01*
X1078220Y-335147D01*
Y-336897D01*
X1078657Y-338647D01*
X1079749Y-340397D01*
X1081059Y-341563D01*
X1082587Y-341855D01*
X1084115Y-341272D01*
X1085644Y-339522D01*
G01X1096375Y-341855D02*
Y-330189D01*
G01Y-332522D02*
X1097467Y-331355D01*
X1098559Y-330480D01*
X1100087Y-330189D01*
X1101178Y-330480D01*
X1102489Y-331355D01*
G01X1143132Y-369355D02*
X1141385Y-369938D01*
X1140075Y-371397D01*
X1139202Y-373146D01*
X1138547Y-375480D01*
X1138329Y-378105D01*
X1138547Y-380730D01*
X1139202Y-383064D01*
X1140075Y-384814D01*
X1141385Y-386272D01*
X1143132Y-386855D01*
X1144878Y-386272D01*
X1146189Y-384814D01*
X1147062Y-383064D01*
X1147717Y-380730D01*
X1147935Y-378105D01*
X1147717Y-375480D01*
X1147062Y-373146D01*
X1146189Y-371397D01*
X1144878Y-369938D01*
X1143132Y-369355D01*
G01X1156484Y-379564D02*
X1158012Y-377522D01*
X1159322Y-376355D01*
X1161069Y-375772D01*
X1162597Y-376355D01*
X1163689Y-377522D01*
X1164562Y-379272D01*
X1164780Y-381313D01*
X1164562Y-383064D01*
X1163689Y-384814D01*
X1162378Y-386272D01*
X1160850Y-386855D01*
X1159104Y-386272D01*
X1157575Y-384522D01*
X1156702Y-381897D01*
X1156484Y-378980D01*
X1156920Y-375189D01*
X1157575Y-373146D01*
X1158667Y-371105D01*
X1160195Y-369647D01*
X1161724Y-369355D01*
X1163252Y-369938D01*
X1164344Y-371397D01*
G01X1174202Y-387438D02*
X1182062Y-369355D01*
G01X1191484Y-372272D02*
X1192794Y-370522D01*
X1194322Y-369647D01*
X1196069Y-369355D01*
X1198252Y-369938D01*
X1199780Y-371397D01*
X1200217Y-373146D01*
X1199999Y-374897D01*
X1199125Y-376355D01*
X1194759Y-379272D01*
X1192794Y-381313D01*
X1191484Y-384231D01*
X1191047Y-386855D01*
X1200217D01*
G01X1213132D02*
Y-369355D01*
X1210512Y-372855D01*
G01Y-386855D02*
X1215752D01*
G01X1226702Y-387438D02*
X1234562Y-369355D01*
G01X1243984Y-372272D02*
X1245294Y-370522D01*
X1246822Y-369647D01*
X1248569Y-369355D01*
X1250752Y-369938D01*
X1252280Y-371397D01*
X1252717Y-373146D01*
X1252499Y-374897D01*
X1251625Y-376355D01*
X1247259Y-379272D01*
X1245294Y-381313D01*
X1243984Y-384231D01*
X1243547Y-386855D01*
X1252717D01*
G01X1265632Y-369355D02*
X1263885Y-369938D01*
X1262575Y-371397D01*
X1261702Y-373146D01*
X1261047Y-375480D01*
X1260829Y-378105D01*
X1261047Y-380730D01*
X1261702Y-383064D01*
X1262575Y-384814D01*
X1263885Y-386272D01*
X1265632Y-386855D01*
X1267378Y-386272D01*
X1268689Y-384814D01*
X1269562Y-383064D01*
X1270217Y-380730D01*
X1270435Y-378105D01*
X1270217Y-375480D01*
X1269562Y-373146D01*
X1268689Y-371397D01*
X1267378Y-369938D01*
X1265632Y-369355D01*
G01X1283132Y-386855D02*
Y-369355D01*
X1280512Y-372855D01*
G01Y-386855D02*
X1285752D01*
G01X1300195D02*
X1300632Y-383064D01*
X1301287Y-379855D01*
X1302160Y-376938D01*
X1303252Y-373730D01*
X1304999Y-369355D01*
X1296265D01*
G01X1190829Y-341855D02*
Y-324355D01*
X1195195D01*
X1196942Y-325230D01*
X1198252Y-326397D01*
X1199344Y-328146D01*
X1200217Y-330189D01*
X1200435Y-333105D01*
X1200217Y-336022D01*
X1199344Y-338064D01*
X1198252Y-339814D01*
X1196942Y-340980D01*
X1195195Y-341855D01*
X1190829D01*
G01X1217062D02*
Y-330189D01*
G01Y-332230D02*
X1216189Y-331064D01*
X1214878Y-330480D01*
X1213350Y-330189D01*
X1211822Y-330772D01*
X1210512Y-331938D01*
X1209638Y-333688D01*
X1209202Y-336022D01*
X1209638Y-338355D01*
X1210512Y-340105D01*
X1211822Y-341272D01*
X1213350Y-341855D01*
X1214878Y-341563D01*
X1216189Y-340689D01*
X1217062Y-339522D01*
G01X1230632Y-324355D02*
Y-341855D01*
G01X1227575Y-330189D02*
X1233689D01*
G01X1244857Y-333980D02*
X1251844D01*
X1251189Y-331938D01*
X1250097Y-330772D01*
X1248569Y-330189D01*
X1247040Y-330480D01*
X1245730Y-331355D01*
X1244857Y-333397D01*
X1244420Y-335147D01*
Y-336897D01*
X1244857Y-338647D01*
X1245949Y-340397D01*
X1247259Y-341563D01*
X1248787Y-341855D01*
X1250315Y-341272D01*
X1251844Y-339522D01*
G54D116*
X735512Y410241D03*
Y377189D03*
G54D107*
X702000Y347771D03*
X678452D03*
G54D23*
X49200Y142500D03*
X44200D03*
X39200D03*
X34200D03*
G54D50*
X71165Y357207D03*
X73725D03*
X76285D03*
Y344407D03*
X73725D03*
X71165D03*
X28465Y357007D03*
X31025D03*
X33585D03*
X36145D03*
Y344207D03*
X33585D03*
X31025D03*
X28465D03*
X49465Y356807D03*
X52025D03*
X54585D03*
X57145D03*
Y344007D03*
X54585D03*
X52025D03*
X49465D03*
X78845Y357207D03*
Y344407D03*
X92260Y357000D03*
X94820D03*
X97380D03*
X99940D03*
Y344200D03*
X97380D03*
X94820D03*
X92260D03*
X234872Y298705D03*
X232312D03*
X229752D03*
X227192D03*
X253215Y298667D03*
X250655D03*
X248095D03*
X245535D03*
X216640Y298700D03*
X214080D03*
X211520D03*
X208960D03*
X227192Y311505D03*
X229752D03*
X232312D03*
X234872D03*
X245535Y311467D03*
X248095D03*
X250655D03*
X253215D03*
X208960Y311500D03*
X211520D03*
X214080D03*
X216640D03*
X272637Y298956D03*
X270077D03*
X267517D03*
X264957D03*
Y311756D03*
X267517D03*
X270077D03*
X272637D03*
G54D41*
X59821Y199950D03*
X57853D03*
X55884D03*
X53916D03*
X51947D03*
X49979D03*
Y219450D03*
X51947D03*
X53916D03*
X55884D03*
X57853D03*
X59821D03*
G54D14*
X56500Y152000D03*
X30400Y292200D03*
Y287700D03*
X65267Y242333D03*
X44900Y266100D03*
X30700Y318500D03*
Y314000D03*
X60800Y403150D03*
X89000Y194900D03*
X87500Y213800D03*
X163500Y113400D03*
X160000Y122000D03*
X163500Y117700D03*
X258700Y90000D03*
Y95000D03*
X211200Y284000D03*
X299835Y104177D03*
X280700Y321600D03*
X274068Y378200D03*
Y382200D03*
X278169Y373425D03*
X372700Y279500D03*
X366200Y293000D03*
X372700Y275500D03*
X372500Y283900D03*
X353200Y308000D03*
X361700Y340500D03*
X374200Y344500D03*
X364727Y312654D03*
X374382Y328503D03*
X343950Y309823D03*
X330038Y405044D03*
X392349Y340563D03*
X473797Y358638D03*
X531315Y335679D03*
Y331679D03*
X632700Y278745D03*
X597200Y346950D03*
X601123Y352729D03*
Y356729D03*
X603987Y322456D03*
Y326656D03*
X625750Y348900D03*
X623250Y353400D03*
X625750Y310491D03*
X623250Y314991D03*
X615250D03*
X615750Y353400D03*
X600773Y378955D03*
Y374955D03*
X620467Y378894D03*
Y374894D03*
X590000Y486650D03*
X584400Y460300D03*
X584470Y468530D03*
X646892Y94236D03*
X639392D03*
X671631Y392433D03*
X676200Y407500D03*
X649420Y395300D03*
X746900Y94500D03*
X731931Y98293D03*
X739400Y86200D03*
Y90300D03*
X746900Y86300D03*
Y90400D03*
X757000Y169550D03*
X753808Y154100D03*
X753800Y160050D03*
X753823Y148245D03*
X757002Y173715D03*
X754668Y164081D03*
X757018Y179053D03*
X757030Y197200D03*
X715200Y217500D03*
X757018Y183153D03*
Y187253D03*
X757030Y206200D03*
X750670Y297120D03*
X757583Y317184D03*
X728670Y423930D03*
X731600Y475400D03*
X760871Y143624D03*
X760850Y139500D03*
X761900Y135400D03*
X798170Y307120D03*
Y302620D03*
G54D32*
X26634Y150171D03*
X35000Y165500D03*
X58962Y161005D03*
X64862Y152205D03*
X58470Y118520D03*
X22839Y163817D03*
X34380Y203183D03*
X74700Y226300D03*
X69000Y226200D03*
X23453Y180973D03*
X76425Y191400D03*
X41617Y183405D03*
X54370Y180718D03*
X68400Y193400D03*
X55800Y226100D03*
X35200Y207400D03*
X76100Y197000D03*
X38850Y222450D03*
X63206Y226229D03*
X40400Y192100D03*
X71850Y216100D03*
X76500Y202400D03*
X59800Y193700D03*
X29650Y235500D03*
X46200Y226200D03*
X51200Y226100D03*
X38814Y180206D03*
X33691Y179468D03*
X69399Y281699D03*
X69500Y276700D03*
X69400Y287100D03*
X35600Y292500D03*
Y287000D03*
Y280800D03*
X56500Y239800D03*
X41450Y256479D03*
X35500Y319100D03*
Y314000D03*
X35918Y307565D03*
X69304Y309100D03*
X69400Y303900D03*
X69200Y314100D03*
X57325Y337545D03*
X62325Y337845D03*
X36325Y337745D03*
X41325Y338045D03*
X43600Y362649D03*
X72446Y364233D03*
X29706Y364053D03*
X72356Y383400D03*
X50486Y364064D03*
X65300Y363049D03*
X22600Y362849D03*
X28200Y382900D03*
X30400Y397100D03*
X64700Y399000D03*
X42076Y383750D03*
X112997Y117234D03*
X112100Y124500D03*
X119700Y124600D03*
X93000Y147000D03*
X84800Y147100D03*
X100900Y147000D03*
X109100Y147100D03*
X116264Y136064D03*
X119700Y147200D03*
X133800Y165900D03*
X77600Y210700D03*
X79050Y217150D03*
X78805Y337855D03*
X84025Y338245D03*
X100270Y337248D03*
X105480Y338030D03*
X79292Y380900D03*
X93641Y364266D03*
X86395Y362842D03*
X99912Y412200D03*
X98614Y391150D03*
X84536Y390405D03*
Y395405D03*
X170050Y109625D03*
X165097Y139545D03*
X164810Y151500D03*
X190424Y122651D03*
X176500Y161200D03*
X184700Y159000D03*
X165319Y134201D03*
X162500Y128600D03*
X176083Y118985D03*
X190461Y128067D03*
X183498Y151582D03*
X183760Y118548D03*
X151697Y131670D03*
X164900Y123300D03*
X143655Y174344D03*
X181489Y208606D03*
X177550Y180450D03*
X153855Y184292D03*
X162523Y183631D03*
X171411Y184292D03*
X194000Y288000D03*
X198700Y289500D03*
X183901Y274213D03*
X259609Y52025D03*
X253613Y61140D03*
X231753Y60341D03*
X236750Y83000D03*
X223544Y74403D03*
X242733Y74428D03*
X250500Y95000D03*
X214350Y81543D03*
X258750Y85000D03*
X223650Y131900D03*
X255993Y130718D03*
X232300Y292200D03*
X251800Y292300D03*
X261600D03*
X246800Y292400D03*
X239700Y292600D03*
X227200Y292300D03*
X220900Y292500D03*
X240000Y298200D03*
X258800Y296500D03*
X221800Y298800D03*
X211300Y292302D03*
X216068Y260413D03*
X204368Y258164D03*
X228668Y262713D03*
X259690Y320875D03*
X245943Y322043D03*
X242091Y327293D03*
X227500Y318900D03*
X226500Y327500D03*
X214200Y324200D03*
X208960Y318800D03*
X221747Y384384D03*
X226200Y400600D03*
X230300Y407700D03*
X235300Y405400D03*
X248204Y372309D03*
X243664Y368975D03*
X243400Y378645D03*
X262672Y460813D03*
X283223Y29000D03*
X283173Y38000D03*
X287963Y33500D03*
X286848Y42500D03*
X296092Y93239D03*
X289398Y96815D03*
X322470Y111347D03*
X300168Y97933D03*
X306595Y98693D03*
X306196Y106297D03*
X311293Y109977D03*
X315932Y104519D03*
X294644Y60800D03*
X294822Y66022D03*
X279615Y88546D03*
X294914Y71626D03*
X271864Y82126D03*
X323484Y105921D03*
X289793Y85901D03*
X268962Y88452D03*
X291970Y76090D03*
X279804Y175047D03*
X292500Y125500D03*
X307369Y115952D03*
X302500Y115000D03*
X301400Y190000D03*
X281000Y218500D03*
X300943Y235180D03*
X273200Y219700D03*
X320628Y238548D03*
X325611Y296231D03*
X313650Y298850D03*
X274376Y250699D03*
X271800Y292600D03*
X266600Y292300D03*
X289817Y283261D03*
X297038Y285956D03*
X282362Y292400D03*
X280087Y283473D03*
X289056Y296534D03*
X316847Y243024D03*
X271468Y272013D03*
X267668Y267313D03*
X291268Y265113D03*
X285268Y269713D03*
X323950Y255200D03*
X265365Y320651D03*
X299791Y352123D03*
X285400Y326792D03*
X299100Y324500D03*
X294950Y317400D03*
X277250Y317700D03*
X279719Y383549D03*
X275782Y388274D03*
X280549Y391744D03*
X269500Y409600D03*
X275500Y413800D03*
X269954Y402990D03*
X283050Y413600D03*
X269977Y373425D03*
X266111Y379351D03*
X381103Y10651D03*
X366929D03*
X352756D03*
X338583D03*
X326632Y122343D03*
X327500Y134028D03*
X359000Y135000D03*
X377000Y289500D03*
X379257Y298785D03*
X377500Y283900D03*
Y277500D03*
X371437Y293000D03*
X361800Y245800D03*
X355700Y242500D03*
X350303Y238898D03*
X344600Y248800D03*
X374513Y265662D03*
X333054Y256852D03*
X356500Y266300D03*
X338054Y256852D03*
X334735Y303062D03*
X378500Y306500D03*
X350750Y343000D03*
X348900Y319600D03*
X350298Y333944D03*
X357895Y309272D03*
X351341Y313694D03*
X364596Y325590D03*
X366042Y318443D03*
X333794Y405044D03*
X326083Y416366D03*
X330531Y416439D03*
X332485Y435750D03*
X437796Y10651D03*
X423622D03*
X409449D03*
X395276D03*
X434083Y148279D03*
X444866Y152736D03*
X448416Y162119D03*
X430409Y335154D03*
X416841Y335528D03*
X395603Y345150D03*
X407304Y343726D03*
X430464Y351272D03*
X410236Y419291D03*
Y404331D03*
Y449212D03*
Y434252D03*
X508661Y10651D03*
X494488D03*
X480315D03*
X466142D03*
X451969D03*
X471096Y110797D03*
X479435Y105501D03*
X482779Y114109D03*
X470537Y105272D03*
X479830Y120100D03*
X477011Y126263D03*
X494472Y123575D03*
X490923Y130166D03*
X487008Y137123D03*
X464994Y146129D03*
X457326Y150586D03*
X472891Y154886D03*
X465088Y157094D03*
X456471Y159418D03*
X459221Y355189D03*
X510200Y359400D03*
X502450Y361450D03*
X494517Y335499D03*
X499517Y335504D03*
X509645Y335582D03*
X504581Y335524D03*
X491474Y342209D03*
X488444Y338409D03*
X486281Y346317D03*
X483500Y336000D03*
X472724Y335567D03*
X565354Y10651D03*
X551181D03*
X537008D03*
X522835D03*
X517097Y338315D03*
X518984Y419591D03*
X552200Y399200D03*
X542300Y399400D03*
X548400Y423600D03*
X566182Y423300D03*
X564415Y380334D03*
X566103Y386434D03*
X559514Y384907D03*
X569152Y378908D03*
X561746Y480600D03*
X551550Y480550D03*
X579527Y10651D03*
X633000Y18000D03*
X632343Y55642D03*
X630888Y284129D03*
X625250Y284066D03*
X602273Y288661D03*
X614273D03*
X608273D03*
X629250Y332319D03*
X597250Y342400D03*
X606225Y356075D03*
X605900Y350800D03*
X610982Y348239D03*
X616800Y348100D03*
X608607Y326656D03*
X612907Y321774D03*
X624108Y322850D03*
X596631Y330137D03*
X608157Y310168D03*
X615900Y309900D03*
X612300Y378500D03*
Y373500D03*
X616600Y394600D03*
X592475Y382413D03*
X605070Y378970D03*
X592513Y376121D03*
X605600Y373500D03*
X622109Y385304D03*
Y364424D03*
X590400Y421200D03*
X625187Y378210D03*
X629602Y375862D03*
X599500Y480000D03*
X624898Y486518D03*
X613000Y484000D03*
X590640Y472600D03*
X600600Y430701D03*
X597140Y473590D03*
X582855Y476795D03*
X595500Y439400D03*
X627718Y473130D03*
X621500Y468000D03*
X633100Y449500D03*
X607500Y487500D03*
X581500Y489700D03*
X660500Y24600D03*
X657000Y46500D03*
X657440Y31815D03*
X660692Y42436D03*
X643103Y17648D03*
X638103Y16800D03*
X665012Y65659D03*
X645078Y61949D03*
X642000Y57500D03*
X636943Y57942D03*
X695151Y255091D03*
X689680Y261152D03*
X689764Y255264D03*
X683390Y302820D03*
X637500Y353500D03*
X652708Y378812D03*
X682000Y372160D03*
X655643Y389328D03*
X683563Y387733D03*
X695700Y385740D03*
X689800Y400850D03*
X663667Y395700D03*
X684100Y382050D03*
X678970Y400560D03*
X681800Y366200D03*
X663706Y423000D03*
X680560Y407500D03*
X661650Y390100D03*
X680000Y473500D03*
X677882Y449120D03*
X690000Y437000D03*
X695980Y432800D03*
X690690Y424820D03*
X751181Y10651D03*
X737007D03*
X722834D03*
X708661D03*
X742523Y100815D03*
X727727Y94148D03*
X719365Y96773D03*
X745700Y149600D03*
X747350Y165050D03*
X744552Y170076D03*
X744300Y160815D03*
X753050Y138650D03*
X749680Y169550D03*
X745351Y144396D03*
X752700Y143850D03*
X748000Y138330D03*
X712720Y229666D03*
X757337Y271913D03*
X760000Y290500D03*
X757483Y305724D03*
Y310924D03*
X716500Y376500D03*
X708337Y390944D03*
X716000Y393000D03*
X721100Y387500D03*
X735943Y475465D03*
X710268Y446055D03*
X700900Y441785D03*
X729837Y428237D03*
X736130Y451570D03*
X714400Y442500D03*
X743160Y428240D03*
X724340Y443410D03*
X784767Y84511D03*
X765615Y157200D03*
X762350Y186150D03*
X770351Y176500D03*
X783390Y286000D03*
X779890Y289000D03*
X767532Y289746D03*
X763840Y271430D03*
X776518Y246482D03*
X767663Y250993D03*
X763505Y316008D03*
X789597Y306335D03*
X789658Y301111D03*
X791520Y327000D03*
G54D126*
G01X47362Y174281D02*
Y170656D01*
X43487Y166781D01*
G01X47362Y174281D02*
X44739D01*
X38814Y180206D01*
G01X39612Y174281D02*
X34425Y179468D01*
X33691D01*
G01X41938Y235454D02*
Y237338D01*
X45650Y241050D01*
Y250280D01*
G01X45938Y235454D02*
Y237238D01*
X49320Y240620D01*
Y250280D01*
G01X34100Y217500D02*
Y219050D01*
X29650Y223500D01*
G01D02*
Y227500D01*
G01D02*
Y235500D01*
G01X35405Y239808D02*
X31466D01*
X29650Y237992D01*
Y235500D01*
G01X45150Y214621D02*
X42204D01*
X39325Y217500D01*
X34100D01*
G01X48010Y219750D02*
Y224390D01*
X46200Y226200D01*
G01X41938Y231954D02*
Y228345D01*
X43737Y226546D01*
X45854D01*
X46200Y226200D01*
G01X51200Y226100D02*
Y227743D01*
X50082Y228861D01*
X47025D01*
X45938Y229948D01*
Y231954D01*
G01X51200Y226100D02*
Y223300D01*
X49979Y222079D01*
Y219450D01*
G01X36405Y184267D02*
Y182615D01*
X38814Y180206D01*
G01X32405Y184267D02*
Y180754D01*
X33691Y179468D01*
G01X56500Y239800D02*
Y234577D01*
X56541Y234536D01*
G01X62500Y282200D02*
X68898D01*
X69399Y281699D01*
G01X74046Y281695D02*
X69403D01*
X69399Y281699D01*
G01X62500Y277200D02*
X69000D01*
X69500Y276700D01*
G01X74046Y276695D02*
X69505D01*
X69500Y276700D01*
G01X62500Y287200D02*
X69300D01*
X69400Y287100D01*
G01X74046Y286695D02*
X69805D01*
X69400Y287100D01*
G01X42500Y292200D02*
X42400Y292100D01*
X36000D01*
X35600Y292500D01*
G01X30450Y292200D02*
X35300D01*
X35600Y292500D01*
G01X30450Y296700D02*
Y292200D01*
G01X42500Y287200D02*
X35800D01*
X35600Y287000D01*
G01X30450Y287700D02*
X34900D01*
X35600Y287000D01*
G01X30450Y283200D02*
Y287700D01*
G01X42500Y282200D02*
X37000D01*
X35600Y280800D01*
G01X30700Y278950D02*
X33750D01*
X35600Y280800D01*
G01X26600Y278950D02*
X30700D01*
G01X65317Y242333D02*
X93884D01*
G01X56500Y239800D02*
Y243019D01*
X52400Y247119D01*
Y266100D01*
X48900Y269600D01*
X42600D01*
X41450Y268450D01*
Y266100D01*
G01X28150Y265800D02*
X41150D01*
X41450Y266100D01*
G01X35650Y261925D02*
X41425D01*
X41450Y261900D01*
G01D02*
Y256479D01*
G01D02*
Y255649D01*
X37469Y251668D01*
Y250280D01*
G01X42404Y319922D02*
X36322D01*
X35500Y319100D01*
G01X30750Y318500D02*
X34900D01*
X35500Y319100D01*
G01X30750Y323000D02*
Y318500D01*
G01X42404Y314922D02*
X36722D01*
X35800Y314000D01*
X35500D01*
G01X30750D02*
X35500D01*
G01X30750Y309500D02*
Y314000D01*
G01X42404Y309922D02*
X38275D01*
X35918Y307565D01*
G01X31400Y305250D02*
X33603D01*
X35918Y307565D01*
G01X27200Y305250D02*
X31400D01*
G01X73950Y309500D02*
X71500D01*
X71100Y309100D01*
X69304D01*
G01X62404Y309922D02*
X68482D01*
X69304Y309100D01*
G01X73950Y304500D02*
X71500D01*
X70900Y303900D01*
X69400D01*
G01X62404Y304922D02*
X66578D01*
X67600Y303900D01*
X69400D01*
G01X62404Y314922D02*
X68378D01*
X69200Y314100D01*
G01X73750Y314000D02*
X69300D01*
X69200Y314100D01*
G01X73725Y357207D02*
Y362954D01*
X72446Y364233D01*
G01X31025Y357007D02*
Y362734D01*
X29706Y364053D01*
G01X54585Y356807D02*
Y360484D01*
X54329Y360740D01*
Y366179D01*
X54800Y366650D01*
G01X58900Y334180D02*
Y335970D01*
X57325Y337545D01*
G01X54585Y344007D02*
Y340285D01*
X57325Y337545D01*
G01X57145Y356807D02*
Y360703D01*
X58567Y362125D01*
Y364817D01*
X60400Y366650D01*
G01X57145Y344007D02*
Y341707D01*
X58376Y340476D01*
X61336D01*
X62325Y339487D01*
Y337845D01*
G01D02*
Y334068D01*
G01X34100Y366850D02*
X33585Y366335D01*
Y357007D01*
G01Y344207D02*
Y340485D01*
X36325Y337745D01*
G01X37900Y334380D02*
Y336170D01*
X36325Y337745D01*
G01X38200Y366850D02*
Y363100D01*
X36145Y361045D01*
Y357007D01*
G01Y344207D02*
Y341907D01*
X37376Y340676D01*
X40336D01*
X41325Y339687D01*
Y338045D01*
G01D02*
Y334268D01*
G01X52025Y356807D02*
Y362525D01*
X50486Y364064D01*
G01X77200Y367050D02*
X76285Y366135D01*
Y357207D01*
G01X78805Y337855D02*
X76285Y340375D01*
Y344407D01*
G01X71165Y357207D02*
Y360084D01*
X70196Y361053D01*
X66171D01*
X65300Y361924D01*
Y363049D01*
G01X28465Y357007D02*
Y359884D01*
X27496Y360853D01*
X23471D01*
X22600Y361724D01*
Y362849D01*
G01X49465Y356807D02*
Y359684D01*
X48496Y360653D01*
X44471D01*
X43600Y361524D01*
Y362649D01*
G01X69300Y372050D02*
X68800Y371550D01*
Y367751D01*
G01X73100Y372050D02*
X69300D01*
G01X72446Y364233D02*
X68928Y367751D01*
X68800D01*
G01X26100Y371602D02*
Y367552D01*
G01X29900Y371602D02*
X26100D01*
G01X29706Y364053D02*
X26207Y367552D01*
X26100D01*
G01X54800Y366650D02*
X57650Y369500D01*
Y375350D01*
X59300Y377000D01*
Y380629D01*
X62071Y383400D01*
X72356D01*
G01D02*
X106709D01*
G01X79292Y380900D02*
X62400D01*
X61300Y379800D01*
Y376900D01*
X63300Y374900D01*
Y369550D01*
X60400Y366650D01*
G01X35800Y363400D02*
Y366400D01*
X35350Y366850D01*
X34100D01*
G01X40100Y363400D02*
Y366100D01*
X39350Y366850D01*
X38200D01*
G01X46900Y371483D02*
Y367650D01*
X47150Y367400D01*
G01X50700Y371483D02*
X46900D01*
G01X50486Y364064D02*
X47150Y367400D01*
G01X65300Y367751D02*
Y363049D01*
G01X65500Y372050D02*
X65300Y371850D01*
Y367751D01*
G01X22600Y367552D02*
Y362849D01*
G01X22000Y371602D02*
Y369966D01*
X22600Y369366D01*
Y367552D01*
G01X43650Y367400D02*
X43600Y367350D01*
Y362649D01*
G01X43000Y371483D02*
X43650Y370833D01*
Y367400D01*
G01X25700Y399450D02*
X32850D01*
X33740Y398560D01*
X36850D01*
G01X37500Y387450D02*
Y388900D01*
X40200Y391600D01*
Y397449D01*
X39089Y398560D01*
X36850D01*
G01X99912Y412200D02*
X32200D01*
X25700Y405700D01*
Y399450D01*
G01X28200Y382900D02*
X30140Y380960D01*
X56460D01*
X61100Y385600D01*
X107041D01*
X112638Y391197D01*
G01X25700Y388450D02*
Y385400D01*
X28200Y382900D01*
G01X36850Y396000D02*
X31500D01*
X30400Y397100D01*
G01X25700Y395950D02*
X26550D01*
X27700Y397100D01*
X30400D01*
G01X25700Y391950D02*
Y395950D01*
G01X60850Y403150D02*
Y399410D01*
X60830Y399390D01*
G01X70757Y397955D02*
X67500D01*
X66455Y399000D01*
X64700D01*
G01X60830Y399390D02*
X64310D01*
X64700Y399000D01*
G01X37500Y383950D02*
X38989D01*
X39189Y383750D01*
X42076D01*
G01X46750Y387500D02*
Y392250D01*
X45560Y393440D01*
X43350D01*
G01X46750Y387500D02*
Y386185D01*
X44315Y383750D01*
X42076D01*
G01X77546Y281695D02*
X80688D01*
G01X77546Y276695D02*
X80688D01*
G01X216068Y260413D02*
X176614D01*
X135326Y301701D01*
Y445311D01*
X125984Y454653D01*
Y464075D01*
G01X204368Y258164D02*
X176034D01*
X133326Y300872D01*
Y442074D01*
X118110Y457290D01*
Y464075D01*
G01X77450Y309500D02*
X80600D01*
X80700Y309400D01*
G01X77450Y304500D02*
X80500D01*
X80600Y304600D01*
G01X94820Y357000D02*
Y363087D01*
X93641Y364266D01*
G01X80600Y334580D02*
X78805Y336375D01*
Y337855D01*
G01X81300Y367050D02*
X80267Y366017D01*
Y362525D01*
X78845Y361103D01*
Y357207D01*
G01X84025Y338245D02*
Y334468D01*
G01X78845Y344407D02*
Y342107D01*
X80076Y340876D01*
X83036D01*
X84025Y339887D01*
Y338245D01*
G01X98295Y366843D02*
X97380Y365928D01*
Y357000D01*
G01Y344200D02*
Y340138D01*
X100270Y337248D01*
G01X102400Y333900D02*
Y335118D01*
X100270Y337248D01*
G01X102395Y366843D02*
X101362Y365810D01*
Y362318D01*
X99940Y360896D01*
Y357000D01*
G01X105480Y338030D02*
X105710Y338260D01*
Y339090D01*
X104131Y340669D01*
X101171D01*
X99940Y341900D01*
Y344200D01*
G01X105480Y338030D02*
X106500Y337010D01*
Y333900D01*
G01X92260Y357000D02*
Y359877D01*
X91291Y360846D01*
X87266D01*
X86395Y361717D01*
Y362842D01*
G01X228668Y262713D02*
X177143D01*
X137326Y302530D01*
Y450090D01*
X133858Y453558D01*
Y464075D01*
G01X112023Y383013D02*
X109910Y380900D01*
X79292D01*
G01X89895Y371676D02*
X93695D01*
G01X89895Y367626D02*
Y371676D01*
G01X93641Y364266D02*
X90281Y367626D01*
X89895D01*
G01X78171Y363195D02*
Y366079D01*
X77200Y367050D01*
G01X82171Y363195D02*
Y366179D01*
X81300Y367050D01*
G01X99266Y362988D02*
Y365872D01*
X98295Y366843D01*
G01X103266Y362988D02*
Y365972D01*
X102395Y366843D01*
G01X86395Y367626D02*
Y362842D01*
G01X85795Y371676D02*
Y369959D01*
X86395Y369359D01*
Y367626D01*
G01X104900Y412200D02*
X99912D01*
G01X98614Y391150D02*
X102679D01*
G01X93700D02*
X98614D01*
G01X107582Y391266D02*
X103916Y387600D01*
X93150D01*
X89600Y391150D01*
G01X77257Y392835D02*
X82106D01*
X84536Y390405D01*
G01X89600Y391150D02*
X87550D01*
X86805Y390405D01*
X84536D01*
G01X77257Y395395D02*
X84526D01*
X84536Y395405D01*
G01X89600Y394650D02*
X88845Y395405D01*
X84536D01*
G01X93700Y394650D02*
X89600D01*
G01X271468Y272013D02*
X179160D01*
X151989Y299184D01*
Y485840D01*
X145929Y491900D01*
X128600D01*
X125984Y489284D01*
Y480807D01*
G01X118110D02*
Y489010D01*
X123000Y493900D01*
X146758D01*
X153989Y486669D01*
Y300013D01*
X179789Y274213D01*
X183901D01*
G01X133858Y480807D02*
Y487658D01*
X136100Y489900D01*
X145100D01*
X149989Y485011D01*
Y298355D01*
X178631Y269713D01*
X285268D01*
G01X164020Y101127D02*
Y104310D01*
G01X163550Y113400D02*
Y109050D01*
G01X164900Y123300D02*
X166100Y124500D01*
X170300D01*
X171694Y125894D01*
Y128547D01*
G01X163550Y117700D02*
Y113400D01*
G01Y117700D02*
Y121950D01*
X164900Y123300D01*
G01X207500Y278400D02*
X203600D01*
X194000Y288000D01*
G01D02*
X192000Y290000D01*
Y302000D01*
X194000Y304000D01*
X200950D01*
X203750Y306800D01*
G01Y298800D02*
Y300450D01*
X202500Y301700D01*
X195900D01*
X194200Y300000D01*
Y294000D01*
X198700Y289500D01*
G01D02*
X201250Y286950D01*
Y284449D01*
X204997Y280702D01*
G01X322650Y266231D02*
X326139D01*
X333150Y273242D01*
Y281800D01*
X328350Y286600D01*
X317395D01*
X317394Y286601D01*
X314492D01*
X303691Y275800D01*
X292700D01*
X291113Y274213D01*
X183901D01*
G01X141732Y480807D02*
Y486932D01*
X142500Y487700D01*
X144300D01*
X147989Y484011D01*
Y297526D01*
X178202Y267313D01*
X267668D01*
G01X291268Y265113D02*
X177572D01*
X139326Y303359D01*
Y449979D01*
X141732Y452385D01*
Y464075D01*
G01X250137Y36053D02*
X260469Y25721D01*
X315903D01*
X319316Y29134D01*
X338583D01*
G01X246530Y66786D02*
Y39660D01*
X250137Y36053D01*
G01X261102Y61140D02*
X253613D01*
G01X250791Y65677D02*
Y61933D01*
X251584Y61140D01*
X253613D01*
G01X255300Y72600D02*
X257315Y70585D01*
X261102D01*
G01X234693Y57400D02*
Y57401D01*
X231753Y60341D01*
G01X227750Y73000D02*
Y74250D01*
X226109Y75891D01*
Y81399D01*
G01X227750Y73000D02*
Y70500D01*
X230250Y68000D01*
G01X231753Y60341D02*
X231752D01*
X230250Y61843D01*
Y68000D01*
G01X279615Y88546D02*
X274510Y83441D01*
Y71336D01*
X274195Y71021D01*
Y71020D01*
X267465Y64290D01*
X261102D01*
G01X271864Y82126D02*
Y71518D01*
X266636Y66290D01*
X265532D01*
X265107Y65865D01*
X261102D01*
G01Y62715D02*
X264661D01*
X265233Y62143D01*
X268147D01*
X278039Y72035D01*
Y82185D01*
G01X250791Y69177D02*
X255154D01*
G01X258750Y95000D02*
X265880D01*
X271130Y100250D01*
X273250D01*
X273273Y100227D01*
X279385D01*
G01X236750Y83000D02*
Y86750D01*
X235601Y87899D01*
X228669D01*
G01X236750Y83000D02*
Y71000D01*
X233750Y68000D01*
G01X233759Y64752D02*
Y67991D01*
X233750Y68000D01*
G01X223549Y81399D02*
Y76049D01*
X223544Y76044D01*
Y74403D01*
G01X220227Y70265D02*
X223971D01*
X223995Y70241D01*
G01X223544Y74403D02*
Y72956D01*
X223995Y72505D01*
Y70241D01*
G01X243049Y81399D02*
Y78930D01*
X242733Y78614D01*
Y74428D01*
G01D02*
Y70261D01*
G01X238880Y70312D02*
X242682D01*
X242733Y70261D01*
G01X255250Y95000D02*
X250500D01*
G01X255250Y90000D02*
Y95000D01*
G01X250500D02*
X249000D01*
X248169Y94169D01*
Y87899D01*
G01X261102Y69010D02*
X263847D01*
X264752Y69915D01*
Y70176D01*
X266618Y72042D01*
Y92493D01*
X272094Y97969D01*
X280511D01*
X281235Y98693D01*
Y102235D01*
X287227Y108227D01*
X292385D01*
G01X261102Y67435D02*
X264840D01*
X268962Y71557D01*
Y88452D01*
G01X258750Y85000D02*
Y90000D01*
G01X245609Y81399D02*
Y71207D01*
X246530Y70286D01*
G01D02*
X247305D01*
X251221Y74202D01*
Y79911D01*
X252832Y81522D01*
X257328D01*
X258750Y82944D01*
Y85000D01*
G01X232312Y298705D02*
Y292212D01*
X232300Y292200D01*
G01X239050Y279700D02*
Y280100D01*
X234800Y284350D01*
G01D02*
X234300D01*
X230700Y287950D01*
G01D02*
Y290600D01*
X232300Y292200D01*
G01X250655Y298667D02*
Y293445D01*
X251800Y292300D01*
G01X252595Y279732D02*
X255131D01*
X256000Y280601D01*
Y284450D01*
G01D02*
X255500D01*
X252000Y287950D01*
G01D02*
Y292100D01*
X251800Y292300D01*
G01X262800Y277835D02*
Y285150D01*
X260000Y287950D01*
G01X264957Y298956D02*
Y293857D01*
X263400Y292300D01*
X261600D01*
G01X260000Y287950D02*
Y291800D01*
X260500Y292300D01*
X261600D01*
G01X248095Y298667D02*
Y293695D01*
X246800Y292400D01*
G01X242400Y289700D02*
X244150D01*
X245800Y288050D01*
G01D02*
Y291400D01*
X246800Y292400D01*
G01X239700Y292600D02*
X238900Y291800D01*
Y287950D01*
G01X245535Y298667D02*
Y295935D01*
X243000Y293400D01*
X240500D01*
X239700Y292600D01*
G01X238900Y287950D02*
X240752D01*
X242402Y286300D01*
G01X229752Y298705D02*
Y294852D01*
X227200Y292300D01*
G01X225500Y278900D02*
X224200Y280200D01*
Y287400D01*
X224750Y287950D01*
X226600D01*
G01D02*
Y291700D01*
X227200Y292300D01*
G01X220900Y292500D02*
X219400Y291000D01*
Y287450D01*
G01X227192Y298705D02*
Y295892D01*
X225900Y294600D01*
X223000D01*
X220900Y292500D01*
G01X219400Y287450D02*
X221006D01*
X222200Y286256D01*
Y277778D01*
X222320Y277658D01*
G01X240200Y303350D02*
Y298400D01*
X240000Y298200D01*
G01D02*
X236900Y295100D01*
Y289075D01*
X235675Y287850D01*
X234800D01*
G01D02*
Y290723D01*
X234872Y290795D01*
Y298705D01*
G01X258700Y300850D02*
X258800Y300750D01*
Y296500D01*
G01X253215Y298667D02*
Y295200D01*
X255300Y293115D01*
Y288650D01*
X256000Y287950D01*
G01D02*
X257050D01*
X257800Y288700D01*
Y295500D01*
X258800Y296500D01*
G01X211520Y298700D02*
Y301780D01*
X209900Y303400D01*
X207150D01*
X203750Y306800D01*
G01X208960Y298700D02*
X206162D01*
X206062Y298800D01*
X203750D01*
G01X222000Y303250D02*
Y301238D01*
X221800Y301038D01*
Y298800D01*
G01X216640Y298700D02*
Y294740D01*
X214400Y292500D01*
Y288350D01*
X215300Y287450D01*
G01D02*
X216400Y288550D01*
Y291527D01*
X221800Y296927D01*
Y298800D01*
G01X214080Y298700D02*
Y295082D01*
X211300Y292302D01*
G01X215300Y283950D02*
X215250Y284000D01*
X211250D01*
G01X211150Y287800D02*
Y284100D01*
X211250Y284000D01*
G01X211150Y287800D02*
Y292152D01*
X211300Y292302D01*
G01X216068Y260413D02*
X305584D01*
X312977Y267806D01*
X322650D01*
G01Y264656D02*
X312656D01*
X306164Y258164D01*
X204368D01*
G01X322650Y270951D02*
X313201D01*
X308050Y265800D01*
X298624D01*
X295537Y262713D01*
X228668D01*
G01X261365Y324351D02*
X259690Y322676D01*
Y320875D01*
G01D02*
Y317764D01*
X261739Y315715D01*
X264114D01*
X264957Y314872D01*
Y311756D01*
G01X245943Y326300D02*
Y322043D01*
G01X248095Y311467D02*
Y314810D01*
X245943Y316962D01*
Y322043D01*
G01X245535Y311467D02*
Y314541D01*
X242091Y317985D01*
Y327293D01*
G01X246100Y329700D02*
X243610D01*
X242091Y328181D01*
Y327293D01*
G01X229752Y311505D02*
Y315108D01*
X227500Y317360D01*
Y318900D01*
G01X230400Y326200D02*
Y323100D01*
X227500Y320200D01*
Y318900D01*
G01X226500Y327500D02*
X224500Y325500D01*
Y317100D01*
X227192Y314408D01*
Y311505D01*
G01X226500Y327500D02*
X228600Y329600D01*
X230400D01*
G01X489600Y367209D02*
X482705Y374104D01*
X318654D01*
X285943Y341393D01*
X275226D01*
X263531Y329698D01*
X253245D01*
G01X299791Y352123D02*
X287061Y339393D01*
X276970D01*
X263804Y326227D01*
X253154D01*
G01X214200Y324200D02*
X216600Y326600D01*
X218400D01*
G01X211520Y311500D02*
Y321520D01*
X214200Y324200D01*
G01X218300Y330000D02*
X216500D01*
X208960Y322460D01*
Y318800D01*
G01D02*
Y311500D01*
G01X259800Y423400D02*
Y420350D01*
X259750Y420300D01*
G01Y412100D02*
Y420300D01*
G01Y412100D02*
Y409500D01*
X257776Y407526D01*
Y405313D01*
G01X308591Y68928D02*
Y46678D01*
X290913Y29000D01*
X283223D01*
G01D02*
X277750D01*
G01Y38000D02*
X283173D01*
G01D02*
X289939D01*
X304591Y52652D01*
Y68928D01*
G01X277750Y33500D02*
X287963D01*
G01D02*
X290885D01*
X306591Y49206D01*
Y71074D01*
X308591Y73074D01*
G01X311182Y58692D02*
Y53110D01*
X329646Y34646D01*
X338583D01*
G01X277750Y42500D02*
X286848D01*
G01D02*
X289564D01*
X302591Y55527D01*
Y71074D01*
X304591Y73074D01*
G01X276700Y66700D02*
X279010Y69010D01*
X283302D01*
G01X459055Y24410D02*
X454437Y29028D01*
Y81563D01*
X453500Y82500D01*
X313814D01*
X303075Y93239D01*
X296092D01*
G01D02*
X289160D01*
X283385Y99014D01*
Y100227D01*
G01X287385D02*
Y98828D01*
X289398Y96815D01*
G01D02*
X290733Y95480D01*
X303877D01*
X314857Y84500D01*
X454400D01*
X456460Y82440D01*
Y32517D01*
X459055Y29922D01*
G01X501575Y24410D02*
X496979Y29006D01*
Y81873D01*
X468781Y110071D01*
X323746D01*
X322470Y111347D01*
G01D02*
X319534Y114283D01*
X319533D01*
G01X291385Y100227D02*
X293679Y97933D01*
X300168D01*
G01X466142Y29134D02*
X461610Y33666D01*
Y82537D01*
X457647Y86500D01*
X315686D01*
X304253Y97933D01*
X300168D01*
G01X295385Y100227D02*
X305061D01*
X306595Y98693D01*
G01X466142Y34646D02*
X463610Y37178D01*
Y83884D01*
X458993Y88501D01*
X456819D01*
X456818Y88500D01*
X316788D01*
X306595Y98693D01*
G01X306196Y106297D02*
Y103369D01*
X318865Y90700D01*
X461730D01*
X468633Y83797D01*
Y29006D01*
X473229Y24410D01*
G01X306196Y110209D02*
Y106297D01*
G01X473229Y29922D02*
X470739Y32412D01*
Y84520D01*
X462559Y92700D01*
X320822D01*
X308710Y104812D01*
Y114611D01*
X307369Y115952D01*
G01X480315Y29134D02*
X475719Y33730D01*
Y83269D01*
X460935Y98053D01*
X319357D01*
X311293Y106117D01*
Y109977D01*
G01D02*
Y113238D01*
X310711Y113820D01*
G01X480315Y34646D02*
X477719Y37242D01*
Y84098D01*
X461764Y100053D01*
X320398D01*
X315932Y104519D01*
G01D02*
X314772Y105679D01*
Y108292D01*
G01X294644Y60800D02*
X287469D01*
X287129Y61140D01*
X283302D01*
G01X300311Y60800D02*
X294644D01*
G01X299885Y104177D02*
Y107727D01*
X300385Y108227D01*
G01X302500Y115000D02*
Y105274D01*
X301403Y104177D01*
X299885D01*
G01X283302Y62715D02*
X287237D01*
X287322Y62800D01*
X291600D01*
X294822Y66022D01*
G01X306280Y82574D02*
X300581Y76875D01*
Y71781D01*
X294822Y66022D01*
G01X279615Y88546D02*
X283393Y92324D01*
Y92325D01*
G01X294914Y71626D02*
Y69219D01*
X290495Y64800D01*
X287802D01*
X287292Y64290D01*
X283302D01*
G01X294914Y71626D02*
Y76208D01*
X301280Y82574D01*
G01X272937Y85862D02*
X271864Y84789D01*
Y82126D01*
G01X487402Y24410D02*
X482806Y29006D01*
Y81840D01*
X462593Y102053D01*
X321974D01*
X316772Y107255D01*
Y111099D01*
X310200Y117671D01*
Y137800D01*
X311851Y139451D01*
Y238028D01*
X316847Y243024D01*
G01X487402Y29922D02*
X484806Y32518D01*
Y84097D01*
X464850Y104053D01*
X327053D01*
X325185Y105921D01*
X323484D01*
G01D02*
X320935D01*
X318773Y108083D01*
G01X494489Y29134D02*
X489893Y33730D01*
Y81839D01*
X465679Y106053D01*
X327882D01*
X325864Y108071D01*
X322705D01*
X313051Y117725D01*
Y137344D01*
X313851Y138144D01*
Y235795D01*
X320712Y242656D01*
X338456D01*
X344600Y248800D01*
G01X283302Y67435D02*
X286641D01*
X289793Y70587D01*
Y85901D01*
G01D02*
Y88337D01*
X292030Y90574D01*
G01X268962Y88452D02*
Y92008D01*
X272510Y95556D01*
X280298D01*
G01X283302Y65865D02*
X286781D01*
X287970Y67054D01*
X289887D01*
X291970Y69137D01*
Y76090D01*
G01D02*
Y78264D01*
X296280Y82574D01*
G01X324026Y115936D02*
X327891Y112071D01*
X469822D01*
X471096Y110797D01*
G01X320628Y238548D02*
X315851Y233771D01*
Y137315D01*
X315051Y136515D01*
Y121449D01*
X318714Y117786D01*
X331407D01*
X333122Y116071D01*
X471908D01*
X506067Y81912D01*
Y37241D01*
X508662Y34646D01*
G01X361800Y245800D02*
X349700D01*
X342202Y238302D01*
X324802D01*
X317851Y231351D01*
Y136486D01*
X317051Y135686D01*
Y122461D01*
X319726Y119786D01*
X332236D01*
X333951Y118071D01*
X472737D01*
X511152Y79656D01*
Y29006D01*
X515748Y24410D01*
G01X321343Y122343D02*
X326632D01*
G01X355700Y242500D02*
X350200D01*
X344000Y236300D01*
X327300D01*
X319851Y228851D01*
Y135657D01*
X319051Y134857D01*
Y133199D01*
X321696Y130554D01*
Y130555D01*
X475761D01*
X527000Y79316D01*
Y79103D01*
X527400Y78703D01*
Y32444D01*
X529922Y29922D01*
G01X321051Y134028D02*
X327500D01*
G01X307369Y115952D02*
X304529Y118792D01*
G01X350303Y238898D02*
X345240Y233835D01*
X328335D01*
X321884Y227384D01*
Y202918D01*
X354782Y170020D01*
Y151568D01*
X354781Y151567D01*
Y149911D01*
X367148Y137544D01*
X477259D01*
X539499Y75304D01*
Y29006D01*
X544095Y24410D01*
G01X391732Y238189D02*
X352995D01*
X346491Y231685D01*
X329685D01*
X323884Y225884D01*
Y204781D01*
X332064Y196601D01*
X358763D01*
X367114Y188250D01*
X381449D01*
X421420Y148279D01*
X434083D01*
G01X324459Y301695D02*
Y297383D01*
X325611Y296231D01*
G01X313650Y298850D02*
Y299700D01*
X315645Y301695D01*
X318459D01*
G01X318050Y296650D02*
X314800D01*
X313650Y297800D01*
Y298850D01*
G01X270077Y298956D02*
Y294323D01*
X271800Y292600D01*
G01X279076Y278333D02*
Y279825D01*
X275600Y283301D01*
Y284450D01*
G01D02*
X272100Y287950D01*
X271600D01*
G01X271800Y292600D02*
Y290331D01*
X271600Y290131D01*
Y287950D01*
G01X266406Y277835D02*
Y279152D01*
X264850Y280708D01*
Y287150D01*
X265650Y287950D01*
X267600D01*
G01X267517Y298956D02*
Y293217D01*
X266600Y292300D01*
G01D02*
X267600Y291300D01*
Y287950D01*
G01X391732Y246063D02*
X388437D01*
X385600Y248900D01*
X348800D01*
X340352Y240452D01*
X322532D01*
X320628Y238548D01*
G01X301460Y281122D02*
Y286825D01*
X299635Y288650D01*
G01X289817Y283261D02*
X288393D01*
X287214Y284440D01*
Y288167D01*
G01X292225Y288267D02*
Y284215D01*
X291271Y283261D01*
X289817D01*
G01X294938Y304389D02*
Y299860D01*
X297135Y297663D01*
Y294503D01*
X294708Y292076D01*
G01X297960Y281122D02*
Y285034D01*
X297038Y285956D01*
G01X294708Y292076D02*
Y288286D01*
X297038Y285956D01*
G01X287214Y291667D02*
X283095D01*
X282362Y292400D01*
G01D02*
X281956Y292806D01*
Y297434D01*
G01D02*
X281938Y297452D01*
Y304389D01*
G01X283491Y278576D02*
X280087Y281980D01*
Y283473D01*
G01D02*
Y285613D01*
X277750Y287950D01*
X275600D01*
G01D02*
Y292201D01*
X272637Y295164D01*
Y298956D01*
G01X292378Y304389D02*
Y299591D01*
X294708Y297261D01*
Y295576D01*
G01D02*
X292342D01*
X291384Y296534D01*
X289056D01*
G01X288536Y314764D02*
Y297054D01*
X289056Y296534D01*
G01X278456Y297434D02*
X279378Y298356D01*
Y304389D01*
G01X278456Y297434D02*
X277300Y298590D01*
Y302800D01*
X275696Y304404D01*
Y314340D01*
G01X391732Y250000D02*
X389141D01*
X386241Y252900D01*
X343041D01*
X334940Y244799D01*
X318622D01*
X316847Y243024D01*
G01X328134Y252720D02*
Y249648D01*
X326236Y247750D01*
X323900D01*
G01X271468Y272013D02*
X291954D01*
X293741Y273800D01*
X304520D01*
X315321Y284601D01*
X316565D01*
X316566Y284600D01*
X327521D01*
X331150Y280971D01*
Y274071D01*
X326460Y269381D01*
X322650D01*
G01Y275676D02*
X326076D01*
X326850Y276450D01*
Y279613D01*
X325763Y280700D01*
X317122D01*
X306222Y269800D01*
X296724D01*
X294237Y267313D01*
X267668D01*
G01X291268Y265113D02*
X294866D01*
X297553Y267800D01*
X307200D01*
X312300Y272900D01*
X312321D01*
X312372Y272951D01*
X318301D01*
X319451Y274101D01*
X322650D01*
G01Y272526D02*
X326776D01*
X328950Y274700D01*
Y280342D01*
X326692Y282600D01*
X316149D01*
X305349Y271800D01*
X294800D01*
X292713Y269713D01*
X285268D01*
G01X344850Y275676D02*
X338413D01*
X327966Y265229D01*
Y259316D01*
X323950Y255300D01*
Y255200D01*
G01X323900Y251250D02*
Y255150D01*
X323950Y255200D01*
G01X267517Y311756D02*
Y315251D01*
X265365Y317403D01*
Y320651D01*
G01D02*
Y324351D01*
G01X299791Y352123D02*
X317195Y369527D01*
X475523D01*
X478250Y366800D01*
G01X281150Y332000D02*
X283701D01*
X285400Y330301D01*
Y326792D01*
G01D02*
Y320850D01*
G01X299100Y324500D02*
Y329600D01*
X298200Y330500D01*
X289400D01*
X288000Y329100D01*
Y318076D01*
X287274Y317350D01*
X285400D01*
G01X299100Y324500D02*
Y316400D01*
X297498Y314798D01*
Y310889D01*
G01X285400Y317350D02*
Y315100D01*
X284498Y314198D01*
Y310889D01*
G01X294950Y321700D02*
Y317400D01*
G01D02*
Y317050D01*
X292378Y314478D01*
Y310889D01*
G01X277250Y317700D02*
Y316250D01*
X279378Y314122D01*
Y310889D01*
G01X277250Y321600D02*
Y317700D01*
G01X269500Y420250D02*
Y422865D01*
X268004Y424361D01*
G01X326588Y405044D02*
X323468D01*
X323448Y405064D01*
G01X265250Y370700D02*
X265191Y370641D01*
Y365309D01*
X266500Y364000D01*
G01X328711Y108053D02*
X467756D01*
X470537Y105272D01*
G01X328600Y114400D02*
X328929Y114071D01*
X470865D01*
X479435Y105501D01*
G01X326632Y122343D02*
X332508D01*
X334780Y120071D01*
X473566D01*
X513153Y80484D01*
Y32517D01*
X515748Y29922D01*
G01X482779Y114109D02*
X474743Y122145D01*
X335577D01*
X331649Y126073D01*
Y126111D01*
G01X479830Y120100D02*
X473375Y126555D01*
X341366D01*
X339049Y124238D01*
G01X335994Y126119D02*
X338430Y128555D01*
X474719D01*
X477011Y126263D01*
G01X327500Y134028D02*
X333158D01*
X334631Y132555D01*
X476590D01*
X532412Y76733D01*
Y33730D01*
X537008Y29134D01*
G01X359000Y135000D02*
X476974D01*
X534413Y77561D01*
Y37241D01*
X537008Y34646D01*
G01X341913Y145049D02*
X344434D01*
X353722Y135761D01*
Y135500D01*
X354222Y135000D01*
X359000D01*
G01X494472Y123575D02*
X478503Y139544D01*
X367977D01*
X356782Y150739D01*
Y170849D01*
X351723Y175908D01*
Y178499D01*
G01X490923Y130166D02*
X479395Y141694D01*
X368656D01*
X358782Y151568D01*
Y171678D01*
X354143Y176317D01*
Y183439D01*
G01X362260Y184360D02*
X357853Y179953D01*
Y175436D01*
X360782Y172507D01*
Y152397D01*
X369335Y143844D01*
X480287D01*
X487008Y137123D01*
G01X348597Y213090D02*
X349822D01*
X350632Y213900D01*
X353829D01*
X364307Y224378D01*
X393669D01*
X395669Y226378D01*
G01X391732D02*
X363478D01*
X353000Y215900D01*
X351012D01*
X349822Y217090D01*
X348597D01*
G01D02*
X345647D01*
X343276Y219461D01*
X341757D01*
G01X364169Y188366D02*
X366838Y185697D01*
X380961D01*
X420529Y146129D01*
X464994D01*
G01X366460Y191794D02*
X368004Y190250D01*
X384121D01*
X423785Y150586D01*
X457326D01*
G01X368558Y194540D02*
X370780Y192318D01*
X387107D01*
X426689Y152736D01*
X444866D01*
G01X379415Y194608D02*
X387646D01*
X427368Y154886D01*
X472891D01*
G01X391732Y234252D02*
X390182D01*
X389430Y233500D01*
X384802D01*
X382372Y235930D01*
X353565D01*
X347320Y229685D01*
X332495D01*
X325884Y223074D01*
Y205610D01*
X332153Y199341D01*
X366587D01*
X369794Y196134D01*
X378112D01*
X378586Y196608D01*
X388475D01*
X427989Y157094D01*
X465088D01*
G01X370570Y198219D02*
X372223D01*
X372802Y198798D01*
X389114D01*
X428494Y159418D01*
X456471D01*
G01X395669Y234252D02*
X393698Y232281D01*
X390881D01*
X389900Y231300D01*
X383954D01*
X381474Y233780D01*
X354466D01*
X348371Y227685D01*
X333324D01*
X327884Y222245D01*
Y206439D01*
X332812Y201511D01*
X389230D01*
X428622Y162119D01*
X448416D01*
G01X344891Y209590D02*
X343858D01*
X342856Y208588D01*
X338603D01*
X335701Y211490D01*
Y215563D01*
G01X348597Y209590D02*
X344891D01*
G01X377000Y289500D02*
X374050D01*
X372550Y288000D01*
G01X377000Y289500D02*
X378300D01*
X380400Y287400D01*
G01X332750Y296855D02*
Y301077D01*
X334735Y303062D01*
G01X366250Y299200D02*
X370750D01*
G01X379257Y298785D02*
X377285D01*
X375149Y296649D01*
X373301D01*
X370750Y299200D01*
G01X382000Y296500D02*
X379715Y298785D01*
X379257D01*
G01X384600Y285600D02*
X382900Y283900D01*
X377500D01*
G01D02*
X372550D01*
G01X325611Y296231D02*
X327559Y294283D01*
X338947D01*
X340250Y292980D01*
G01X372750Y275500D02*
X376500D01*
X377500Y276500D01*
Y277500D01*
G01X372750Y279500D02*
X376500D01*
X377500Y278500D01*
Y277500D01*
G01X379000Y272600D02*
X373750D01*
X372700Y273650D01*
Y275450D01*
X372750Y275500D01*
G01X366250Y293000D02*
X371437D01*
G01D02*
X382400D01*
X384300Y291100D01*
G01X361800Y245800D02*
X363770D01*
X365070Y244500D01*
X394106D01*
X395669Y246063D01*
G01X355700Y242500D02*
X389006D01*
X389380Y242126D01*
X391732D01*
G01X395669D02*
X393747Y240204D01*
X351609D01*
X350303Y238898D01*
G01X344600Y248800D02*
X346700Y250900D01*
X386100D01*
X388550Y248450D01*
X394119D01*
X395669Y250000D01*
G01X344850Y274101D02*
X339765D01*
X332000Y266336D01*
G01X374513Y265662D02*
X376633Y263542D01*
Y261543D01*
G01X344850Y272526D02*
X353474D01*
X359000Y267000D01*
X373175D01*
X374513Y265662D01*
G01X340280Y253765D02*
X334455D01*
X333054Y255166D01*
Y256852D01*
G01X344850Y270951D02*
X339451D01*
X334500Y266000D01*
Y261385D01*
X333054Y259939D01*
Y256852D01*
G01X337500Y266050D02*
X340831Y269381D01*
X344850D01*
G01X358096Y262268D02*
Y264704D01*
X356500Y266300D01*
G01D02*
X354994Y267806D01*
X344850D01*
G01X338054Y256852D02*
X337500Y257406D01*
Y261800D01*
X341931Y266231D01*
X344850D01*
G01X338054Y256852D02*
X338206Y256700D01*
X341998D01*
G01X368610Y257299D02*
X367950Y257959D01*
X365387D01*
G01X344850Y264656D02*
X351344D01*
X353500Y262500D01*
G01X365387Y257959D02*
X358041D01*
X353500Y262500D01*
G01X376633Y256851D02*
X375654Y257830D01*
X372119D01*
G01D02*
X369189Y254900D01*
X355799D01*
X353556Y257143D01*
G01X344850Y263081D02*
X347618D01*
X353556Y257143D01*
G01X343000Y305750D02*
X358750D01*
X362672Y309672D01*
X381437D01*
X385887Y305222D01*
G01X334735Y303062D02*
X337423Y305750D01*
X343000D01*
G01X370750Y303200D02*
X374050Y306500D01*
X378500D01*
G01X370750Y303200D02*
X366250D01*
G01X378500Y306500D02*
X380396D01*
X381396Y305500D01*
Y302610D01*
G01X340500Y309823D02*
X335882D01*
G01X350750Y347500D02*
Y343000D01*
G01D02*
Y339404D01*
X348596Y337250D01*
G01X345141Y319717D02*
X348783D01*
X348900Y319600D01*
G01D02*
Y317000D01*
X347750Y315850D01*
G01X352396Y337200D02*
Y336042D01*
X350298Y333944D01*
G01X345121Y331500D02*
X347854D01*
X350298Y333944D01*
G01X361750Y340500D02*
Y339500D01*
X364050Y337200D01*
G01X361750Y340500D02*
X370750D01*
G01X374250Y344500D02*
Y347600D01*
G01X384000Y344500D02*
X374250D01*
G01X361277Y312654D02*
Y313723D01*
X359200Y315800D01*
G01X353250Y308000D02*
X356623D01*
X357895Y309272D01*
G01D02*
X361277Y312654D01*
G01X349750Y308000D02*
Y312103D01*
X351341Y313694D01*
G01D02*
X353447Y315800D01*
X355200D01*
G01X364596Y325590D02*
X361990D01*
X360300Y323900D01*
G01X370932Y323750D02*
X368250D01*
X366410Y325590D01*
X364596D01*
G01X370932Y323750D02*
Y328503D01*
G01X366042Y318443D02*
X366807Y319208D01*
X369890D01*
X370932Y320250D01*
G01X363400Y315800D02*
Y315801D01*
X366042Y318443D01*
G01X330088Y405044D02*
X333794D01*
G01X330531Y409111D02*
Y407369D01*
X330088Y406926D01*
Y405044D01*
G01X333794D02*
X337575D01*
X337592Y405027D01*
G01X326083Y409116D02*
Y407186D01*
X326588Y406681D01*
Y405044D01*
G01X326083Y412616D02*
Y416366D01*
G01D02*
Y418564D01*
X327365Y419846D01*
Y422661D01*
G01X329925Y429161D02*
Y419012D01*
X330531Y418406D01*
Y416439D01*
G01D02*
Y412611D01*
G01X332458Y439668D02*
Y443488D01*
X332436Y443510D01*
G01X332485Y435750D02*
Y439641D01*
X332458Y439668D01*
G01X332485Y435750D02*
Y429161D01*
G01X558268Y29922D02*
X555672Y32518D01*
Y74535D01*
X481928Y148279D01*
X434083D01*
G01X444866Y152736D02*
X483129D01*
X562759Y73106D01*
Y37242D01*
X565355Y34646D01*
G01X448416Y162119D02*
X485062D01*
X576933Y70248D01*
Y69900D01*
X576932Y69899D01*
Y37242D01*
X579528Y34646D01*
G01X395669Y238189D02*
X393580Y236100D01*
X389000D01*
G01X403543Y238189D02*
X401575Y236221D01*
G01X407480Y238189D02*
X405512Y236221D01*
G01X415354Y238189D02*
X417322Y236221D01*
G01X403543Y234252D02*
X401575Y232284D01*
G01X401727Y228641D02*
X403401Y230315D01*
X403543D01*
G01X407480Y234252D02*
X405512Y232284D01*
G01X415354Y234252D02*
X413386Y232284D01*
G01X407480Y230315D02*
X405512Y228347D01*
G01X411417Y261811D02*
X409449Y259843D01*
G01X427165Y289371D02*
X425197Y291339D01*
G01X435039Y293308D02*
X433071Y295276D01*
G01X435039Y297245D02*
X433071Y299213D01*
G01X435039Y289371D02*
X433071Y291339D01*
G01X450787Y289371D02*
X448819Y287403D01*
G01X446850Y289371D02*
X448818Y291339D01*
G01X446850Y293308D02*
X448818Y295276D01*
G01X438976Y297245D02*
X437008Y299213D01*
G01X438976Y289371D02*
X437008Y291339D01*
G01X431102Y297245D02*
X429134Y295277D01*
G01X431102Y301182D02*
X429134Y299214D01*
G01X435039Y285434D02*
X437007Y287402D01*
G01X431102Y293308D02*
X429134Y291340D01*
G01X427165Y297245D02*
X425197Y299213D01*
G01X431102Y289371D02*
X429134Y287403D01*
G01X442913Y293308D02*
X440945Y295276D01*
G01X442913Y297245D02*
X440945Y299213D01*
G01X442913Y289371D02*
X440945Y291339D01*
G01X442913Y285434D02*
X440945Y287402D01*
G01X438976Y293308D02*
X437008Y295276D01*
G01X419291Y253937D02*
X417323Y251969D01*
G01X415354Y250000D02*
X413386Y248032D01*
G01X407480Y250000D02*
X405512Y248032D01*
G01X423228Y253937D02*
X421260Y251969D01*
G01X407480Y246063D02*
X405512Y244095D01*
G01X403543Y246063D02*
X401575Y244095D01*
G01X415354Y246063D02*
X413386Y244095D01*
G01X419291Y250000D02*
X417323Y248032D01*
G01X403543Y242126D02*
X401575Y240158D01*
G01X407480Y242126D02*
X405512Y240158D01*
G01X431102Y285434D02*
X433070Y287402D01*
G01X415354Y242126D02*
Y242125D01*
X413387Y240158D01*
G01X423228Y250000D02*
X421260Y248032D01*
G01X419291Y246063D02*
X417323Y244095D01*
G01X415354Y253937D02*
X413386Y251969D01*
G01X403543Y250000D02*
X401575Y248032D01*
G01X423228Y297245D02*
X421260Y295277D01*
G01X419291Y242126D02*
X421259Y240158D01*
G01X423228Y246063D02*
X421260Y244095D01*
G01X419291Y238189D02*
X417323Y240157D01*
G01X423228Y301182D02*
X421260Y299214D01*
G01X427165Y293308D02*
X425197Y295276D01*
G01X415354Y312993D02*
X413386Y311025D01*
G01X427165Y316930D02*
X425197Y318898D01*
G01X427165Y301182D02*
X425197Y303150D01*
G01X431102Y312993D02*
X429134Y314961D01*
G01X431102Y309056D02*
X429134Y311024D01*
G01X450787Y309056D02*
X448819Y307088D01*
G01X451400Y340750D02*
X447300D01*
G01X444100Y341000D02*
Y340500D01*
X446362Y338238D01*
Y335520D01*
X446708Y335174D01*
Y334466D01*
X445775Y333533D01*
Y332825D01*
X446482Y332118D01*
X447190D01*
X448123Y333051D01*
X448831D01*
X449538Y332344D01*
Y331636D01*
X448605Y330703D01*
Y329995D01*
X449312Y329288D01*
X450020D01*
X450953Y330221D01*
X451661D01*
X452624Y329258D01*
Y324273D01*
X450787Y322436D01*
Y320867D01*
G01X444200Y337600D02*
Y332200D01*
X450787Y325613D01*
Y324804D01*
G01X446850Y309056D02*
X448818Y311024D01*
G01X446850Y305119D02*
X448818Y303151D01*
G01X446850Y312993D02*
X444882Y314961D01*
G01X446850Y316930D02*
X444882Y318898D01*
G01X435039Y320867D02*
Y322125D01*
X437144Y324230D01*
Y329566D01*
X437760Y330182D01*
Y337439D01*
X437500Y337699D01*
Y340750D01*
G01D02*
X438380D01*
X440300Y338830D01*
Y337500D01*
G01X435039Y312993D02*
X433071Y314961D01*
G01X431102Y331263D02*
Y324804D01*
G01X427165D02*
Y329563D01*
X423500Y333228D01*
Y339058D01*
X421357Y341201D01*
G01X421375Y346552D02*
X424117Y343810D01*
Y341270D01*
X425500Y339887D01*
Y335281D01*
X428796Y331985D01*
Y323869D01*
X427165Y322238D01*
Y320867D01*
G01X431102Y305119D02*
X429134Y303151D01*
G01X427165Y312993D02*
X425197Y314961D01*
G01X430409Y335154D02*
Y334491D01*
X433489Y331411D01*
Y324681D01*
X431102Y322294D01*
Y320867D01*
G01X427700Y340550D02*
X430409Y337841D01*
Y335154D01*
G01X416841Y340334D02*
Y335528D01*
G01D02*
Y332159D01*
X418500Y330500D01*
X422500D01*
X424927Y328073D01*
Y323927D01*
X423228Y322228D01*
Y320867D01*
G01X419291Y309056D02*
X417323Y311024D01*
G01X431102Y316930D02*
X429134Y318898D01*
G01X442800Y330300D02*
X444550Y328550D01*
Y325950D01*
X445696Y324804D01*
X446850D01*
G01X446200Y327400D02*
X446900D01*
X448700Y325600D01*
Y324320D01*
X446850Y322470D01*
Y320867D01*
G01X442913Y301182D02*
X440945Y303150D01*
G01X442913Y309056D02*
X440945Y311024D01*
G01X442913Y305119D02*
X440945Y307087D01*
G01X442913Y320867D02*
X444881Y322835D01*
G01X442913Y324804D02*
Y327204D01*
G01X438976Y320867D02*
X440944Y322835D01*
G01X438976Y324804D02*
Y327204D01*
G01Y316930D02*
X437008Y318898D01*
G01X438976Y312993D02*
X437008Y314961D01*
G01X438976Y309056D02*
X437008Y311024D01*
G01X438976Y301182D02*
X437008Y303150D01*
G01X438976Y305119D02*
X437008Y307087D01*
G01X432200Y341500D02*
X435350Y338350D01*
Y336733D01*
X435039Y336422D01*
Y324804D01*
G01Y316930D02*
X433071Y318898D01*
G01X392399Y340563D02*
Y337659D01*
X392959Y337099D01*
G01X400300Y345150D02*
X395603D01*
G01D02*
X393462D01*
X392399Y344087D01*
Y340563D01*
G01X423228Y324804D02*
X421260Y326772D01*
G01X419291Y320867D02*
X421259Y322835D01*
G01X423228Y316930D02*
X421260Y318898D01*
G01X423228Y312993D02*
X421260Y314961D01*
G01X415354Y320867D02*
X417322Y322835D01*
G01X415354Y316930D02*
X413386Y314962D01*
G01X423228Y309056D02*
X421260Y307088D01*
G01X405921Y347159D02*
X407292Y345788D01*
Y343738D01*
X407304Y343726D01*
G01X412400Y340334D02*
X408773D01*
X407292Y341815D01*
Y343714D01*
X407304Y343726D01*
G01X430464Y347078D02*
Y351272D01*
G01D02*
Y356373D01*
G01X435039Y301182D02*
X433071Y303150D01*
G01X423228Y305119D02*
X421260Y303151D01*
G01X485500Y432820D02*
X435773D01*
X425197Y422244D01*
G01X485500Y427520D02*
X445433D01*
X425197Y407284D01*
G01X490800Y427520D02*
X488191Y430129D01*
X439578D01*
X422244Y412795D01*
G01X425197Y452165D02*
X431762Y445600D01*
X488620D01*
X490800Y443420D01*
G01X485500D02*
X430330D01*
X422244Y451506D01*
Y457677D01*
G01X425197Y437205D02*
X426112Y438120D01*
X485500D01*
G01X422244Y442717D02*
X424461Y440500D01*
X488420D01*
X490800Y438120D01*
G01X422244Y427756D02*
X429758Y435270D01*
X488350D01*
X490800Y432820D01*
G01X471096Y110797D02*
X498979Y82914D01*
Y32518D01*
X501575Y29922D01*
G01X479435Y105501D02*
X504066Y80870D01*
Y33730D01*
X508662Y29134D01*
G01X470537Y105272D02*
X491893Y83916D01*
Y37242D01*
X494489Y34646D01*
G01X522835Y29134D02*
X518239Y33730D01*
Y78649D01*
X482779Y114109D01*
G01X522835Y34646D02*
X520248Y37233D01*
Y79682D01*
X479830Y120100D01*
G01X529922Y24410D02*
X525400Y28932D01*
Y77874D01*
X477011Y126263D01*
G01X494472Y123575D02*
X541499Y76548D01*
Y32518D01*
X544095Y29922D01*
G01X490923Y130166D02*
X546585Y74504D01*
Y33730D01*
X551181Y29134D01*
G01X487008Y137123D02*
X548585Y75546D01*
Y37242D01*
X551181Y34646D01*
G01X464994Y146129D02*
X481249D01*
X553672Y73706D01*
Y29006D01*
X558268Y24410D01*
G01X457326Y150586D02*
X482450D01*
X560759Y72277D01*
Y33730D01*
X565355Y29134D01*
G01X572441Y24410D02*
X567845Y29006D01*
Y70849D01*
X483808Y154886D01*
X472891D01*
G01X465088Y157094D02*
X484429D01*
X569845Y71678D01*
Y32518D01*
X572441Y29922D01*
G01X456471Y159418D02*
X484934D01*
X574932Y69420D01*
Y33730D01*
X579528Y29134D01*
G01X498032Y202756D02*
X500000Y200788D01*
G01X501969Y202756D02*
X503937Y200788D01*
G01X466536Y301182D02*
X468504Y299214D01*
G01X474410Y285434D02*
X472442Y287402D01*
G01X478347Y293308D02*
X480315Y295276D01*
G01X482284Y297245D02*
X484252Y295277D01*
G01X474410Y289371D02*
X476378Y291339D01*
G01X450787Y285434D02*
X452755Y287402D01*
G01X450787Y293308D02*
X452755Y291340D01*
G01X450787Y297245D02*
X452755Y295277D01*
G01X470473Y289371D02*
X472441Y291339D01*
G01X466536Y285434D02*
X464568Y287402D01*
G01X458662Y297245D02*
X460630Y299213D01*
G01X482284Y289371D02*
X480316Y287403D01*
G01X482284Y293308D02*
X484252Y291340D01*
G01X482284Y285434D02*
X484252Y287402D01*
G01X486221Y293308D02*
X488189Y295276D01*
G01X458662Y293308D02*
X456694Y295276D01*
G01X478347Y289371D02*
X480315Y291339D01*
G01X454725Y289371D02*
X456693Y291339D01*
G01X458662Y289371D02*
X460630Y291339D01*
G01X523602Y345779D02*
Y341689D01*
X509912Y327999D01*
X509101D01*
X505906Y324804D01*
G01X501969Y312993D02*
X500001Y314961D01*
G01X509843Y324804D02*
X511255D01*
X521231Y334780D01*
X522352D01*
X526160Y338588D01*
X528806D01*
X531850Y341632D01*
Y342777D01*
X533333Y344260D01*
X548483D01*
X552200Y340543D01*
Y339300D01*
G01X505906Y320867D02*
Y322100D01*
X508193Y324387D01*
Y325488D01*
X509159Y326454D01*
X510133D01*
X510678Y326999D01*
X510969D01*
X518469Y334499D01*
X519242D01*
X525331Y340588D01*
X527765D01*
X528902Y341725D01*
G01X501969Y316930D02*
X503937Y318898D01*
G01X517097Y338315D02*
X505236Y326454D01*
X505222D01*
X504256Y325488D01*
Y324376D01*
X501969Y322089D01*
Y320867D01*
G01X486221Y305119D02*
X488189Y307087D01*
G01X490158Y309056D02*
X492126Y311024D01*
G01X465300Y351481D02*
X466470Y350311D01*
Y342159D01*
X470301Y338328D01*
Y336672D01*
X469755Y336126D01*
Y332443D01*
X464536Y327224D01*
Y324548D01*
X462599Y322611D01*
Y320867D01*
G01X458662Y305119D02*
X460630Y307087D01*
G01X454725Y305119D02*
X456693Y307087D01*
G01X458662Y309056D02*
X460630Y311024D01*
G01X462599Y324804D02*
Y327204D01*
G01X454725Y309056D02*
X456693Y311024D01*
G01X464327Y340751D02*
X465049D01*
X468300Y337500D01*
G01D02*
X466840Y336040D01*
Y334587D01*
X468071Y333356D01*
Y332648D01*
X467364Y331941D01*
X466656D01*
X465369Y333229D01*
X464663D01*
X463953Y332519D01*
Y331813D01*
X465241Y330526D01*
Y329818D01*
X464534Y329111D01*
X463826D01*
X463087Y329850D01*
X462379D01*
X460746Y328217D01*
Y323738D01*
X458662Y321654D01*
Y320867D01*
G01X454725Y312993D02*
X456693Y314961D01*
G01X464300Y337500D02*
Y334970D01*
X458662Y329332D01*
Y324804D01*
G01X460327Y340751D02*
X461049D01*
X464300Y337500D01*
G01X450787Y305119D02*
X452755Y307087D01*
G01X450787Y301182D02*
X452755Y303150D01*
G01X454725Y316930D02*
X456693Y318898D01*
G01X455900Y341100D02*
Y339743D01*
X454700Y338543D01*
Y324829D01*
X454725Y324804D01*
G01X451400Y340750D02*
X453250D01*
X453600Y341100D01*
X455900D01*
G01X460300Y333500D02*
Y335000D01*
X459800Y335500D01*
X457500D01*
X456910Y334910D01*
Y324588D01*
X454725Y322403D01*
Y320867D01*
G01X482284Y301182D02*
X484252Y303150D01*
G01X494095Y316930D02*
X496063Y318898D01*
G01X486221Y309056D02*
X488189Y311024D01*
G01X482284Y305119D02*
X484252Y307087D01*
G01X482284Y320867D02*
Y321784D01*
X484671Y324171D01*
Y325554D01*
X492367Y333250D01*
Y336390D01*
X492594Y336617D01*
Y337894D01*
X494077Y339377D01*
Y345637D01*
X493700Y346014D01*
Y347200D01*
X493200Y347700D01*
G01X510200Y359400D02*
Y363209D01*
G01X514000Y351550D02*
X513750Y351800D01*
X512652D01*
X510750Y353702D01*
Y358850D01*
X510200Y359400D01*
G01X502450Y361450D02*
X502950Y360950D01*
Y354402D01*
X504852Y352500D01*
X505950D01*
X506200Y352250D01*
G01X507337Y345313D02*
X508175Y346151D01*
Y350275D01*
X506200Y352250D01*
G01Y363209D02*
X503309D01*
X502450Y362350D01*
Y361450D01*
G01X494095Y324804D02*
Y335077D01*
X494517Y335499D01*
G01X497900Y341850D02*
Y338882D01*
X494517Y335499D01*
G01X499517Y335504D02*
X502700Y338687D01*
Y341850D01*
G01X499517Y335504D02*
X496000Y331987D01*
Y323971D01*
X494095Y322066D01*
Y320867D01*
G01X494400Y363800D02*
Y363500D01*
X492950Y362050D01*
X492947D01*
X489950Y359053D01*
Y354402D01*
X491852Y352500D01*
X492950D01*
X493200Y352250D01*
G01D02*
X496200Y349250D01*
Y347050D01*
X497900Y345350D01*
G01X499100Y363409D02*
X498809D01*
X496450Y361050D01*
Y353402D01*
X497555Y352297D01*
X499221D01*
X499700Y352250D01*
G01D02*
X500288Y350662D01*
Y346512D01*
X501450Y345350D01*
X502700D01*
G01X509645Y335582D02*
X500000Y325937D01*
Y324000D01*
X498032Y322032D01*
Y320867D01*
G01X509645Y335582D02*
Y337612D01*
X512754Y340721D01*
Y341734D01*
G01X504581Y335524D02*
X498032Y328975D01*
Y324804D01*
G01X504581Y335524D02*
X506543Y337486D01*
Y341019D01*
X507337Y341813D01*
G01X518020Y343632D02*
X515254Y340866D01*
Y339423D01*
X513267Y337436D01*
Y336102D01*
X501969Y324804D01*
G01X494095Y312993D02*
X496063Y314961D01*
G01X486627Y354924D02*
Y353760D01*
X490444Y349943D01*
Y349356D01*
X490468Y349332D01*
Y347370D01*
X491474Y346364D01*
Y342209D01*
G01D02*
Y340074D01*
X490594Y339194D01*
Y337518D01*
X490476Y337400D01*
Y332996D01*
X482284Y324804D01*
G01X474410Y309056D02*
X476378Y311024D01*
G01X482427Y354924D02*
X482634D01*
X488444Y349114D01*
Y338409D01*
G01D02*
Y333063D01*
X484041Y328660D01*
X479259D01*
X476796Y326197D01*
Y324620D01*
X474410Y322234D01*
Y320867D01*
G01X470473Y305119D02*
X472441Y307087D01*
G01X486281Y346317D02*
Y348448D01*
X481929Y352800D01*
X480302D01*
X478298Y354804D01*
G01X474410Y324804D02*
Y325226D01*
X479427Y330243D01*
X482902D01*
X486281Y333622D01*
Y346317D01*
G01X486221Y301182D02*
X488189Y303150D01*
G01X519263Y327092D02*
X517671D01*
X512000Y321421D01*
Y319087D01*
X509843Y316930D01*
G01X538436Y330918D02*
X534713Y327195D01*
X525071D01*
X520116Y322240D01*
Y320574D01*
X514411Y314869D01*
X512559D01*
X510683Y312993D01*
X509843D01*
G01X498032Y309056D02*
X500000Y307088D01*
G01X501969Y309056D02*
X503937Y311024D01*
G01X466536Y305119D02*
X468504Y303151D01*
G01X470473Y320867D02*
Y322449D01*
X472463Y324439D01*
Y329837D01*
G01X458662Y301182D02*
X460630Y303150D01*
G01X462599Y305119D02*
X464567Y303151D01*
G01X478250Y362400D02*
X478298Y362352D01*
Y358304D01*
G01X501969Y305119D02*
X503937Y307087D01*
G01X547315Y331738D02*
X547271Y331694D01*
X546765D01*
X546047Y330976D01*
X543997D01*
X542007Y328986D01*
X541776D01*
X541694Y328904D01*
X539330D01*
X538777Y328351D01*
X538698D01*
X535542Y325195D01*
X525882D01*
X521116Y320429D01*
Y320159D01*
X518456Y317499D01*
Y312622D01*
X516834Y311000D01*
X511787D01*
X509843Y309056D01*
G01X505906D02*
X507874Y311024D01*
G01X462599Y309056D02*
X464567Y307088D01*
G01X470473Y309056D02*
X468505Y307088D01*
G01X470473Y312993D02*
X472441Y314961D01*
G01X490158Y305119D02*
X492126Y307087D01*
G01X519629Y330448D02*
X519424D01*
X509843Y320867D01*
G01X494095Y309056D02*
X496063Y311024D01*
G01X462599Y312993D02*
X464567Y311025D01*
G01X462599Y316930D02*
X464567Y318898D01*
G01X476500Y340750D02*
X480700D01*
G01X470473Y316930D02*
X472441Y318898D01*
G01X479640Y334674D02*
Y337223D01*
X480700Y338283D01*
Y340750D01*
G01X470473Y324804D02*
Y327204D01*
G01X466536Y309056D02*
X468504Y311024D01*
G01X488189Y322835D02*
Y318898D01*
X486221Y316930D01*
G01X477650Y350800D02*
X481100D01*
X484131Y347769D01*
Y339000D01*
X483500Y338369D01*
Y336000D01*
G01X466536Y320867D02*
X468086Y322417D01*
Y327812D01*
X472789Y332515D01*
X481515D01*
X483500Y334500D01*
Y336000D01*
G01X477650Y350800D02*
X473847Y354603D01*
Y358638D01*
G01X469996Y350962D02*
X470544Y350414D01*
Y346837D01*
X469719Y346012D01*
Y343327D01*
X472296Y340750D01*
G01X472724Y335567D02*
Y340322D01*
X472296Y340750D01*
G01X472724Y335567D02*
Y333940D01*
X466536Y327752D01*
Y324804D01*
G01X478250Y366800D02*
Y362400D01*
G01X523602Y345779D02*
X525388Y347565D01*
X528894D01*
G01X532894D02*
X530750Y345421D01*
Y345250D01*
X528902Y343402D01*
Y341725D01*
G01X517097Y338315D02*
X520506Y341724D01*
Y349906D01*
X522000Y351400D01*
G01X512754Y345234D02*
Y346796D01*
X512076Y347474D01*
Y349148D01*
X514000Y351072D01*
Y351550D01*
G01X518020Y343632D02*
Y345831D01*
X516288Y347563D01*
Y349117D01*
X518000Y350829D01*
Y351400D01*
G01X527865Y331679D02*
X525398D01*
X523032Y329313D01*
X521484D01*
X519263Y327092D01*
G01X513780Y320867D02*
X516353D01*
X524681Y329195D01*
X533673D01*
X535336Y330858D01*
Y331772D01*
G01D02*
X535883D01*
X538476Y334365D01*
G01X541714Y331753D02*
X540865Y330904D01*
X538450D01*
X538436Y330918D01*
G01X551394Y331738D02*
Y330694D01*
X550394Y329694D01*
X547594D01*
X546876Y328976D01*
X544826D01*
X542622Y326772D01*
X540027D01*
X536450Y323195D01*
X526734D01*
X519600Y316061D01*
Y312210D01*
X516446Y309056D01*
X513780D01*
G01X554685Y333410D02*
X553013Y331738D01*
X551394D01*
G01X543646Y342347D02*
X544565Y341428D01*
Y334098D01*
X546175Y332488D01*
X546565D01*
X547315Y331738D01*
G01X527865Y335679D02*
X527028D01*
X521797Y330448D01*
X519629D01*
G01X562460Y462070D02*
Y457580D01*
G01X632416Y31609D02*
X633423D01*
X635791Y29241D01*
Y25268D01*
G01X627603Y43523D02*
Y54344D01*
X628901Y55642D01*
X632343D01*
G01X633000Y18000D02*
X628839D01*
X627500Y19339D01*
G01X633000Y18000D02*
X634617D01*
X638941Y22324D01*
Y25268D01*
G01X640516Y47468D02*
Y51558D01*
X639893Y52181D01*
Y53449D01*
X637700Y55642D01*
X632343D01*
G01X642000Y57500D02*
X635000Y64500D01*
X627500D01*
G01X636943Y57942D02*
X633385Y61500D01*
X629500D01*
G01X625750Y162500D02*
X626800D01*
X628446Y160854D01*
X645150D01*
X646456Y162160D01*
Y162204D01*
G01X643307D02*
X642657Y162854D01*
X629275D01*
X626250Y165879D01*
Y166500D01*
G01D02*
Y168134D01*
X627464Y169348D01*
Y173443D01*
G01X623566Y179499D02*
X620125D01*
X616500Y175874D01*
Y172546D01*
X619538Y169508D01*
X620778D01*
X621750Y168536D01*
Y166500D01*
G01D02*
X622250Y166000D01*
Y162500D01*
G01X629250Y278745D02*
Y280147D01*
X630888Y281785D01*
Y284129D01*
G01D02*
Y286346D01*
X629250Y287984D01*
Y288745D01*
G01D02*
Y294229D01*
X626738Y296741D01*
X625224D01*
X624646Y297319D01*
X621320D01*
G01X625250Y278745D02*
Y284066D01*
G01D02*
Y288745D01*
G01X621320Y295354D02*
X625296D01*
X626550Y294100D01*
Y290045D01*
X625250Y288745D01*
G01X600787Y284017D02*
X602273Y285503D01*
Y288661D01*
G01X600787Y280017D02*
Y284017D01*
G01X605020Y295354D02*
X601204D01*
X600450Y294600D01*
Y290700D01*
X602273Y288877D01*
Y288661D01*
G01X597450Y324750D02*
X589648Y316948D01*
Y277289D01*
X593248Y273689D01*
X609294D01*
X613211Y277606D01*
Y280155D01*
G01X597450Y320750D02*
X591648Y314948D01*
Y278648D01*
X594507Y275789D01*
X606024D01*
X608711Y278476D01*
Y280155D01*
G01X621320Y303224D02*
X617524D01*
X616500Y302200D01*
Y296646D01*
X614273Y294419D01*
Y288661D01*
G01X613211Y283655D02*
Y285539D01*
X614273Y286601D01*
Y288661D01*
G01X608273D02*
Y291713D01*
X614000Y297440D01*
Y302550D01*
X617450Y306000D01*
X625000D01*
X626000Y305000D01*
Y302000D01*
X625259Y301259D01*
X621320D01*
G01X608711Y283655D02*
Y286131D01*
X608273Y286569D01*
Y288661D01*
G01X629250Y332319D02*
Y334066D01*
X628364Y334952D01*
X626048D01*
X625272Y335728D01*
X621320D01*
G01X629250Y327654D02*
Y332319D01*
G01X631800Y322750D02*
Y323743D01*
X629250Y326293D01*
Y327654D01*
G01X597250Y337900D02*
X597200Y337950D01*
Y342350D01*
X597250Y342400D01*
G01Y337900D02*
X599600D01*
X601772Y335728D01*
X605020D01*
G01X593750Y346950D02*
X597250Y343450D01*
Y342400D01*
G01X601173Y356729D02*
X603274D01*
X603928Y356075D01*
X606225D01*
G01X605020Y361815D02*
Y360163D01*
X606225Y358958D01*
Y356075D01*
G01X614220Y361815D02*
X610561D01*
X608725Y359979D01*
Y355038D01*
X608550Y354863D01*
Y352423D01*
X606927Y350800D01*
X605900D01*
G01X601173Y352729D02*
X603625D01*
X605554Y350800D01*
X605900D01*
G01X597673Y356729D02*
X594671D01*
X594400Y357000D01*
G01X597673Y352729D02*
X594671D01*
X594400Y353000D01*
G01X615800Y353400D02*
Y351629D01*
X612410Y348239D01*
X610982D01*
G01X619800Y353400D02*
X615800D01*
G01X610982Y348239D02*
X605855D01*
X603899Y346283D01*
X603654D01*
X603321Y345950D01*
X602527D01*
X600980Y344403D01*
Y342396D01*
X601743Y341633D01*
X605020D01*
G01X622300Y348900D02*
X617600D01*
X616800Y348100D01*
G01X605020Y339668D02*
X610839D01*
X614500Y343329D01*
Y345800D01*
X616800Y348100D01*
G01X608607Y326656D02*
X604037D01*
G01X608607D02*
X611056D01*
X613745Y329345D01*
Y339245D01*
X616133Y341633D01*
X621320D01*
G01Y339668D02*
X617221D01*
X615800Y338247D01*
Y324500D01*
X613074Y321774D01*
X612907D01*
G01X604037Y322456D02*
X606318D01*
X607000Y321774D01*
X612907D01*
G01X625250Y327654D02*
Y323992D01*
X624108Y322850D01*
G01X625250Y327654D02*
Y332750D01*
X624237Y333763D01*
X621320D01*
G01X624108Y322850D02*
X618900D01*
G01X597250Y334350D02*
X599663D01*
X600250Y333763D01*
X605020D01*
G01X597250Y334350D02*
Y330756D01*
X596631Y330137D01*
G01D02*
X592763D01*
X592400Y330500D01*
X590350D01*
G01X600537Y326656D02*
X599356D01*
X597450Y324750D01*
G01X600537Y322456D02*
X599156D01*
X597450Y320750D01*
G01X605020Y303224D02*
X601113D01*
X600594Y303743D01*
Y308464D01*
X602298Y310168D01*
X608157D01*
G01X615300Y314991D02*
X610477Y310168D01*
X608157D01*
G01X619800Y314991D02*
X615300D01*
G01X615900Y309900D02*
X613100Y307100D01*
Y305100D01*
X609259Y301259D01*
X605020D01*
G01X615900Y309900D02*
X616491Y310491D01*
X622300D01*
G01X605020Y367725D02*
X608147D01*
X609600Y369178D01*
Y375800D01*
X612300Y378500D01*
G01X617017Y378894D02*
X612694D01*
X612300Y378500D01*
G01X614220Y367725D02*
Y369925D01*
X612300Y371845D01*
Y373500D01*
G01X617017Y374894D02*
X613694D01*
X612300Y373500D01*
G01X601090Y395220D02*
Y393077D01*
X601805Y392362D01*
X604219D01*
X605020Y391561D01*
Y390105D01*
G01X612400Y395220D02*
X615980D01*
X616600Y394600D01*
G01D02*
Y393500D01*
X614220Y391120D01*
Y390105D01*
G01X597323Y378955D02*
X595933D01*
X592475Y382413D01*
G01X589394Y384572D02*
X590316D01*
X592475Y382413D01*
G01X600823Y378955D02*
X601278Y378500D01*
X604600D01*
X605070Y378970D01*
G01X605020Y384195D02*
Y382440D01*
X605600Y381860D01*
Y379500D01*
X605070Y378970D01*
G01X597323Y374955D02*
X593679D01*
X592513Y376121D01*
G01X589391Y378202D02*
X590432D01*
X592513Y376121D01*
G01X605600Y373500D02*
X607100Y375000D01*
Y376860D01*
X608597Y378357D01*
Y382365D01*
X610427Y384195D01*
X614220D01*
G01X600823Y374955D02*
X602278Y373500D01*
X605600D01*
G01X622109Y385304D02*
X627078D01*
G01X614220Y386165D02*
X618282D01*
X619143Y385304D01*
X622109D01*
G01Y364424D02*
X627078D01*
G01X614220Y363785D02*
X620584D01*
X621223Y364424D01*
X622109D01*
G01X595420Y426720D02*
Y426330D01*
X593060Y423970D01*
X591215D01*
X590400Y423155D01*
Y421200D01*
G01X599400Y417046D02*
X594554D01*
X590400Y421200D01*
G01X620517Y378894D02*
X623126D01*
X623810Y378210D01*
X625187D01*
G01X627140Y381353D02*
Y379227D01*
X626123Y378210D01*
X625187D01*
G01X631140Y381353D02*
Y377400D01*
X629602Y375862D01*
G01X620517Y374894D02*
X628634D01*
X629602Y375862D01*
G01X594200Y395200D02*
X594220Y395220D01*
X597590D01*
G01X619400Y417046D02*
X610296D01*
X597590Y404340D01*
Y395220D01*
G01X608900D02*
X604832D01*
G01X609400Y405234D02*
Y395720D01*
X608900Y395220D01*
G01X595440Y430440D02*
X595420Y430420D01*
Y426720D01*
G01X648386Y25268D02*
Y28769D01*
X651456Y31839D01*
X657416D01*
X657440Y31815D01*
G01X664301D02*
X657440D01*
G01X648386Y47468D02*
Y58641D01*
X645078Y61949D01*
G01X647216Y31601D02*
Y29974D01*
X646811Y29569D01*
Y25268D01*
G01X667900Y40800D02*
X666264Y42436D01*
X660692D01*
G01D02*
X648564D01*
X646811Y44189D01*
Y47468D01*
G01X645236Y25268D02*
Y28704D01*
X643816Y30124D01*
Y31573D01*
G01X640144Y40969D02*
X637366Y43747D01*
Y47468D01*
G01X643661D02*
Y51111D01*
X644151Y51601D01*
Y55349D01*
X642000Y57500D01*
G01X642091Y25268D02*
Y20659D01*
X643103Y19647D01*
Y17648D01*
G01D02*
Y13803D01*
G01X664301Y35315D02*
Y40104D01*
G01X656500Y63250D02*
Y56650D01*
X663152Y49998D01*
X664301D01*
G01X638103Y13100D02*
Y16800D01*
G01X640516Y25268D02*
Y21047D01*
X638103Y18634D01*
Y16800D01*
G01X642091Y47468D02*
Y54080D01*
X638229Y57942D01*
X636943D01*
G01X640416Y31609D02*
X644700Y35893D01*
Y44187D01*
X645236Y44723D01*
Y47468D01*
G01X647103Y13964D02*
Y18476D01*
X643661Y21918D01*
Y25268D01*
G01X645078Y61949D02*
X641003Y66024D01*
Y68809D01*
G01X659055Y168504D02*
X660629Y170078D01*
G01X659055Y171653D02*
X660629Y173227D01*
G01X655905Y159055D02*
X654330Y157480D01*
G01X651181Y154330D02*
X652756Y155905D01*
G01X659055Y159055D02*
X660630Y160630D01*
G01X640775Y156218D02*
X642994D01*
X643307Y155905D01*
G01X646456D02*
X648031Y157480D01*
G01X637343Y171335D02*
X638165D01*
X640996Y168504D01*
X643307D01*
G01X637343Y174835D02*
X640125D01*
X643307Y171653D01*
G01X659055Y155905D02*
X657480Y154330D01*
G01X644882Y173228D02*
X646456Y171654D01*
Y171653D01*
G01X644882Y176378D02*
X646456Y174804D01*
Y174803D01*
G01Y168504D02*
X644882Y170078D01*
G01X648031D02*
X649605Y168504D01*
X649606D01*
G01X643307Y174803D02*
X643306D01*
X640509Y177600D01*
G01X679452Y209815D02*
Y202289D01*
X677952Y200789D01*
Y200000D01*
G01X681102D02*
Y201142D01*
X682452Y202492D01*
Y211048D01*
X682048Y211452D01*
Y212199D01*
X682050Y212201D01*
Y213784D01*
X682535Y214269D01*
Y216158D01*
X675437Y223256D01*
Y241152D01*
X685033Y250748D01*
X690860D01*
X695151Y255039D01*
Y255091D01*
G01X667353Y226882D02*
Y220815D01*
X667166Y220628D01*
Y217194D01*
G01X668504Y203149D02*
Y213301D01*
X667166Y214639D01*
Y217194D01*
G01X658610Y226925D02*
Y222250D01*
X657920Y221560D01*
G01D02*
Y215730D01*
X663952Y209698D01*
Y202544D01*
X665354Y201142D01*
Y200000D01*
G01X664452Y222315D02*
Y214430D01*
X666859Y212023D01*
Y198355D01*
X665354Y196850D01*
G01X662204D02*
X660580Y195226D01*
X658586D01*
X657489Y196323D01*
Y197651D01*
X656665Y198475D01*
X655294D01*
X654555Y199214D01*
Y206293D01*
X641579Y219269D01*
Y221770D01*
G01Y227140D02*
Y221770D01*
G01X663110Y226925D02*
Y225610D01*
X661452Y223952D01*
Y217241D01*
G01X665354Y203149D02*
Y210698D01*
X661452Y214600D01*
Y217241D01*
G01X654464Y217358D02*
Y214871D01*
X660452Y208883D01*
Y202826D01*
X662204Y201074D01*
Y200000D01*
G01X654464Y227065D02*
Y217358D01*
G01X671508Y220824D02*
X671653Y220679D01*
Y203149D01*
G01X650684Y221630D02*
Y215822D01*
X659055Y207451D01*
Y203149D01*
G01X650287Y227024D02*
Y222027D01*
X650684Y221630D01*
G01X646318Y217778D02*
Y217359D01*
X657629Y206048D01*
Y199182D01*
X659055Y197756D01*
Y196850D01*
G01X646318Y217778D02*
Y222950D01*
X645968Y223300D01*
Y227047D01*
G01X696850Y196850D02*
X695275Y198425D01*
G01X682700Y233750D02*
Y223300D01*
G01D02*
Y221651D01*
X688225Y216126D01*
Y210554D01*
X690551Y208228D01*
Y203149D01*
G01X689680Y261152D02*
X670135Y241607D01*
Y225505D01*
X669353Y224723D01*
Y214423D01*
X670135Y213641D01*
Y201631D01*
X668504Y200000D01*
G01X692125Y198423D02*
X693699Y196849D01*
X693700D01*
Y196850D01*
G01Y203149D02*
Y209439D01*
X692381Y210758D01*
Y217628D01*
X690887Y219122D01*
Y222466D01*
X691721Y223300D01*
G01X701500Y219000D02*
Y206708D01*
X698452Y203660D01*
Y201602D01*
X696850Y200000D01*
G01X701500Y225500D02*
Y223471D01*
X699350Y221321D01*
Y206359D01*
X696850Y203859D01*
Y203149D01*
G01X686900Y233750D02*
Y227500D01*
G01X690551Y200000D02*
Y200551D01*
X692350Y202350D01*
Y208539D01*
X690270Y210619D01*
Y216910D01*
X686900Y220280D01*
Y227500D01*
G01X695600D02*
Y223139D01*
X695194Y222733D01*
Y201494D01*
X693700Y200000D01*
G01X695600Y233750D02*
X691100D01*
G01X695600D02*
Y227500D01*
G01X690551Y196850D02*
X689201Y198200D01*
Y207370D01*
X686225Y210346D01*
Y215297D01*
X678500Y223022D01*
Y227500D01*
G01D02*
Y233750D01*
G01X679527Y198424D02*
X677953Y196850D01*
X677952D01*
G01X689764Y255264D02*
X687800Y253300D01*
X684756D01*
X673436Y241980D01*
Y222428D01*
X680108Y215756D01*
Y214926D01*
X681050Y213984D01*
Y212616D01*
X681042Y212608D01*
Y210559D01*
X681102Y210499D01*
Y209131D01*
X681042Y209071D01*
Y203209D01*
X681102Y203149D01*
G01X677952D02*
X678452Y203649D01*
Y207892D01*
X677035Y209309D01*
Y215211D01*
X675264Y216982D01*
G01X704708Y264647D02*
X704707D01*
X695151Y255091D01*
G01X695383Y266855D02*
X689680Y261152D01*
G01X695375Y260875D02*
X689764Y255264D01*
G01X658601Y401800D02*
X658820D01*
X658840Y401780D01*
Y398110D01*
G01X676250Y407500D02*
X680560D01*
G01D02*
X682995D01*
X687015Y411520D01*
G01X670494Y425456D02*
Y418996D01*
X670610Y418880D01*
G01D02*
X673900D01*
G01X658840Y394610D02*
X658900D01*
X661380Y397090D01*
Y402000D01*
X668150Y408770D01*
Y428110D01*
X668650Y428610D01*
X672040D01*
X673054Y429624D01*
Y431956D01*
G01X654770Y394610D02*
X658840D01*
G01X661650Y390100D02*
Y388393D01*
X665000Y385043D01*
Y382565D01*
G01X654770Y394610D02*
X657980Y391400D01*
X660350D01*
X661650Y390100D01*
G01X701325Y420610D02*
X692480D01*
X690890Y419020D01*
G01X700855Y426719D02*
X698100Y429474D01*
Y431900D01*
X697200Y432800D01*
X695980D01*
G01X695380Y428300D02*
Y432200D01*
X695980Y432800D01*
G01X683250Y433300D02*
Y437813D01*
G01X690690Y424820D02*
X686390D01*
G01X690690D02*
X695360D01*
X695380Y424800D01*
G01D02*
X701890D01*
X705200Y428110D01*
G01X722834Y29134D02*
X727448Y33748D01*
Y72444D01*
X729640Y74636D01*
X750773D01*
G01X722834Y34646D02*
X725420Y37232D01*
Y73552D01*
X728535Y76667D01*
X747919D01*
G01X737007Y34646D02*
Y35307D01*
X740946Y39246D01*
Y67367D01*
X743163Y69584D01*
X790401D01*
X801546Y80729D01*
Y176640D01*
X806618Y181712D01*
Y218195D01*
X781723Y243090D01*
X779910D01*
X776518Y246482D01*
G01X737007Y29134D02*
Y30298D01*
X733327Y33978D01*
Y69326D01*
X736137Y72136D01*
X788328D01*
X797302Y81110D01*
Y129335D01*
X798900Y130933D01*
Y140303D01*
X796265Y142938D01*
Y185272D01*
X804118Y193125D01*
Y214538D01*
X767663Y250993D01*
G01X722673Y105444D02*
X720697Y107420D01*
Y113610D01*
X722047Y114960D01*
G01X736785Y110185D02*
X733046Y113924D01*
Y115461D01*
X731961Y116546D01*
X730990D01*
X729426Y118110D01*
X728346D01*
G01X734645D02*
X735190D01*
X742600Y110700D01*
X744700D01*
X746000Y112000D01*
X758770D01*
X761770Y115000D01*
X763500D01*
G01X737800Y106525D02*
X736080Y108245D01*
X732955D01*
X730046Y111154D01*
Y113510D01*
X731496Y114960D01*
G01X717197Y109646D02*
Y113260D01*
X718897Y114960D01*
G01X726100Y107200D02*
Y108700D01*
X723485Y111315D01*
Y113249D01*
X725196Y114960D01*
G01X731496Y121260D02*
X732941Y119815D01*
X735085D01*
X742250Y112650D01*
X744050D01*
X745400Y114000D01*
X757941D01*
X763441Y119500D01*
X765500D01*
G01X734709Y106595D02*
X734104Y107200D01*
X732500D01*
X728346Y111354D01*
Y111811D01*
G01X731000Y106315D02*
Y107106D01*
X726896Y111210D01*
Y112412D01*
X727700Y113216D01*
Y114314D01*
X728346Y114960D01*
G01X748500Y109750D02*
X746000D01*
X745800Y109550D01*
X742220D01*
X735110Y116660D01*
X733677D01*
X732227Y118110D01*
X731496D01*
G01X754000Y109600D02*
X751391D01*
X749391Y107600D01*
X742005D01*
X734645Y114960D01*
G01X731496Y111811D02*
X732396D01*
X734212Y109995D01*
G01X728481Y98293D02*
X727797D01*
X725943Y100147D01*
G01D02*
X723383Y102707D01*
X721106D01*
X719715Y104098D01*
X718444D01*
X713950Y108592D01*
Y113162D01*
X715748Y114960D01*
G01X725196Y111811D02*
Y111495D01*
X728000Y108691D01*
Y106700D01*
X730035Y104665D01*
X744528D01*
X744963Y105100D01*
X750427D01*
X750577Y105250D01*
X756450D01*
X762183Y99517D01*
Y99516D01*
X768659Y93040D01*
X771610D01*
G01X718897Y111811D02*
X719010Y111698D01*
Y107281D01*
G01X707649Y110002D02*
Y113161D01*
X709448Y114960D01*
G01X703149Y111811D02*
Y106617D01*
X704154Y105612D01*
X707388D01*
X709035Y103965D01*
X711935D01*
X716216Y99684D01*
Y91198D01*
X722459Y84955D01*
X726039D01*
G01X743450Y86300D02*
X739550D01*
X739450Y86200D01*
G01X726039Y84955D02*
X727594Y83400D01*
X738300D01*
X739450Y84550D01*
Y86200D01*
G01X750950Y97800D02*
X749430D01*
X746864Y100366D01*
X745000D01*
X744551Y100815D01*
X742523D01*
G01X715748Y111811D02*
X714950Y111013D01*
Y109007D01*
X718859Y105098D01*
X720130D01*
X721521Y103707D01*
X724900D01*
X727792Y100815D01*
X742523D01*
G01X751023Y93565D02*
Y97727D01*
X750950Y97800D01*
G01X712598Y114960D02*
X711248Y113610D01*
Y108464D01*
X719756Y99956D01*
X720919D01*
X726727Y94148D01*
X727727D01*
G01X739450Y90300D02*
Y91700D01*
X737850Y93300D01*
X734700D01*
X733457Y94543D01*
X729599D01*
X729204Y94148D01*
X727727D01*
G01X739450Y90300D02*
X741447D01*
X741547Y90400D01*
X743450D01*
G01X719365Y96773D02*
X724346Y91792D01*
X731642D01*
X731900Y92050D01*
G01X719365Y96773D02*
X717525Y98613D01*
Y100772D01*
X713135Y105162D01*
X709339D01*
X706700Y107801D01*
Y108022D01*
X705913Y108809D01*
Y111425D01*
X706299Y111811D01*
G01X703149Y114960D02*
X701799Y113610D01*
Y106552D01*
X703739Y104612D01*
X706973D01*
X708868Y102717D01*
X710721D01*
X714216Y99222D01*
Y90369D01*
X723285Y81300D01*
X761200D01*
X766050Y86150D01*
X781850D01*
X783489Y84511D01*
X784767D01*
G01X710517Y106823D02*
X709448Y107892D01*
Y111811D01*
G01X737100Y95600D02*
X735229D01*
X734286Y96543D01*
X727161D01*
X722025Y101679D01*
X720435D01*
X719016Y103098D01*
X718029D01*
X712950Y108177D01*
Y111459D01*
X712598Y111811D01*
G01X737100Y95600D02*
X739600D01*
X740700Y94500D01*
X743450D01*
G01X759023Y97440D02*
Y99025D01*
X755298Y102750D01*
X751613D01*
X751463Y102600D01*
X744963D01*
X744598Y102965D01*
X727947D01*
X721835Y109077D01*
Y111599D01*
X722047Y111811D01*
G01X759023Y97440D02*
Y94536D01*
X758052Y93565D01*
X755523D01*
G01X801618Y210116D02*
Y194161D01*
X793765Y186308D01*
Y141499D01*
X796400Y138864D01*
Y132857D01*
X794802Y131259D01*
Y82262D01*
X787176Y74636D01*
X750773D01*
G01X747919Y76667D02*
X786149D01*
X792802Y83320D01*
Y131493D01*
X791765Y132530D01*
Y187137D01*
X798400Y193772D01*
Y210898D01*
X801618Y214116D01*
G01X704849Y107385D02*
Y113510D01*
X706299Y114960D01*
G01X734645Y152756D02*
X739856D01*
X743012Y149600D01*
X745700D01*
G01X750373Y148245D02*
X747582D01*
X746227Y149600D01*
X745700D01*
G01X731496Y162204D02*
X732902Y160798D01*
X736293D01*
X740795Y165300D01*
X747100D01*
X747350Y165050D01*
G01D02*
X748319Y164081D01*
X751218D01*
G01D02*
Y165881D01*
X752168Y166831D01*
X755879D01*
X755910Y166800D01*
X760000D01*
X762550Y164250D01*
Y164200D01*
G01X728346Y155905D02*
X729921Y157480D01*
G01X731496Y124409D02*
X731981D01*
X733614Y122776D01*
X735491D01*
X741217Y117050D01*
X743921D01*
X744971Y116000D01*
X756900D01*
X760450Y119550D01*
G01X755300Y131150D02*
X753150Y133300D01*
X749250D01*
X746220Y136330D01*
X745501D01*
X744300Y137531D01*
Y138909D01*
X740394Y142815D01*
X735137D01*
X734645Y143307D01*
G01X739952Y120649D02*
X736192Y124409D01*
X734645D01*
G01X740952Y126815D02*
X740200Y127567D01*
Y128486D01*
X737978Y130708D01*
X734645D01*
G01X707874Y116535D02*
X709448Y118109D01*
Y118110D01*
G01X743100Y114700D02*
X741670D01*
X735110Y121260D01*
X734645D01*
G01X749200Y126250D02*
X747521D01*
X743999Y129772D01*
Y130792D01*
X742089Y132702D01*
X740816D01*
X738160Y135358D01*
X733146D01*
X731496Y137008D01*
G01X737352Y145885D02*
X736781Y146456D01*
X734645D01*
G01X728346Y121260D02*
X726771Y122835D01*
G01X728346Y124409D02*
X729921Y122834D01*
G01X737702Y128565D02*
X736967Y129300D01*
X732904D01*
X731496Y130708D01*
G01X728346Y133858D02*
X729921Y132283D01*
G01Y129134D02*
X728347Y130708D01*
X728346D01*
G01X712598Y118110D02*
X711023Y116535D01*
G01X764900Y130800D02*
X762400Y128300D01*
X759341D01*
X753041Y122000D01*
X746113D01*
X742998Y125115D01*
Y127103D01*
X737808Y132293D01*
X734173D01*
X732608Y133858D01*
X731496D01*
G01X760500Y126000D02*
X754500Y120000D01*
X745308D01*
X738393Y126915D01*
X735289D01*
X734645Y127559D01*
G01X728346Y165354D02*
X726771Y163779D01*
G01X741754Y134617D02*
X741272Y135099D01*
Y137692D01*
X740164Y138800D01*
X734092D01*
X732735Y140157D01*
X731496D01*
G01X728346Y137008D02*
X729921Y135433D01*
G01X739622Y137008D02*
X734645D01*
G01X728346Y140157D02*
X729921Y138582D01*
G01X734645Y140157D02*
X740116D01*
X740473Y139800D01*
X740579D01*
X742300Y138079D01*
Y136500D01*
X744050Y134750D01*
Y133337D01*
X745750Y131637D01*
Y130850D01*
X747700Y128900D01*
X756800D01*
X758200Y130300D01*
X759500D01*
X760100Y130900D01*
G01X729921Y144882D02*
X728347Y146456D01*
X728346D01*
G01X731496Y127559D02*
X733140Y125915D01*
X737020D01*
X744935Y118000D01*
X755658D01*
X763458Y125800D01*
X765800D01*
G01X715748Y118110D02*
X714173Y116535D01*
G01X718897Y118110D02*
X717322Y116535D01*
G01X706299Y127559D02*
X707873Y129133D01*
G01X754000Y126250D02*
X751750Y124000D01*
X746942D01*
X743999Y126943D01*
Y127872D01*
X738013Y133858D01*
X734645D01*
G01X722047Y118110D02*
X720473Y116536D01*
G01X706299Y118110D02*
X704725Y116536D01*
G01X753552Y173715D02*
X750095D01*
X749480Y173100D01*
X747979D01*
X744955Y170076D01*
X744552D01*
G01X731496Y165354D02*
X732394D01*
X733744Y164004D01*
X735459D01*
X741531Y170076D01*
X744552D01*
G01X750358Y154100D02*
Y155458D01*
X752100Y157200D01*
X765615D01*
G01X750358Y154100D02*
X747409D01*
X745604Y155905D01*
X734645D01*
G01X753568Y179053D02*
X751753D01*
X747860Y175160D01*
X746510D01*
X742767Y171417D01*
X740708D01*
X734645Y165354D01*
G01X723622Y116535D02*
X725196Y118109D01*
Y118110D01*
G01X703149Y127559D02*
X704723Y129133D01*
G01X750400Y131050D02*
X748671D01*
X745050Y134671D01*
Y135165D01*
X743300Y136915D01*
Y138494D01*
X739979Y141815D01*
X732988D01*
X731496Y143307D01*
G01X700000Y127559D02*
X701574Y129133D01*
G01X734645Y159055D02*
X736616D01*
X739393Y161832D01*
X743283D01*
X744300Y160815D01*
G01X750350Y160050D02*
X745065D01*
X744300Y160815D01*
G01X709448Y127559D02*
X711022Y129133D01*
G01X731496Y155905D02*
X732728D01*
X734078Y154555D01*
X741218D01*
X741973Y153800D01*
X744856D01*
X747306Y151350D01*
X760100D01*
X768900Y142550D01*
Y134800D01*
G01X712598Y127559D02*
X714172Y129133D01*
G01X728346Y127559D02*
X729921Y125984D01*
G01X709448Y171653D02*
X711023Y173228D01*
G01X731496Y174803D02*
X732846Y173453D01*
X737180D01*
X737668Y172965D01*
X741002D01*
X741152Y173115D01*
X741952D01*
G01X753568Y183153D02*
X751990D01*
X741952Y173115D01*
G01X738352Y174615D02*
X738164Y174803D01*
X734645D01*
G01X728346D02*
X729920Y173229D01*
G01X734645Y171653D02*
X736219Y170079D01*
G01X731496Y171653D02*
X733070Y170079D01*
G01X731496Y149606D02*
X733033Y148069D01*
X738006D01*
X745414Y140661D01*
X749239D01*
X751250Y138650D01*
X753050D01*
G01D02*
X755200D01*
X758450Y135400D01*
G01X746750Y157700D02*
X746719Y157669D01*
X734121D01*
X732735Y159055D01*
X731496D01*
G01X749680Y169550D02*
X753550D01*
G01X749680D02*
X747370D01*
X745746Y167926D01*
X741554D01*
X735832Y162204D01*
X734645D01*
G01Y149606D02*
X738484D01*
X743249Y144841D01*
X744906D01*
X745351Y144396D01*
G01X757400Y139500D02*
X755550Y141350D01*
X751550D01*
X750205Y142695D01*
X747052D01*
X745351Y144396D01*
G01X728346Y149606D02*
X729921Y148031D01*
G01X728346Y143307D02*
X729921Y141732D01*
G01X728346Y162204D02*
X729921Y163779D01*
G01X731496Y152756D02*
X732122D01*
X733472Y151406D01*
X738676D01*
X743083Y146999D01*
X745999D01*
X748303Y144695D01*
X751855D01*
X752700Y143850D01*
G01X757421Y143624D02*
X752926D01*
X752700Y143850D01*
G01X748000Y138330D02*
X746330D01*
X741860Y142800D01*
X741824D01*
X740809Y143815D01*
X736047D01*
X735205Y144657D01*
X733295D01*
X731496Y146456D01*
G01X750550Y135200D02*
Y135450D01*
X748000Y138000D01*
Y138330D01*
G01X729921Y160629D02*
X728347Y159055D01*
X728346D01*
G01X703149Y118110D02*
X701575Y116536D01*
G01X729921Y154330D02*
X728347Y152756D01*
X728346D01*
G01X699600Y233750D02*
Y230555D01*
X701500Y228655D01*
Y225500D01*
G01X770351Y176500D02*
X755350D01*
X753568Y178282D01*
Y179053D01*
G01X715467Y210507D02*
Y205401D01*
X717400Y203468D01*
Y201497D01*
X718897Y200000D01*
G01X725750Y217522D02*
X725678Y217450D01*
X719300D01*
G01D02*
X715467Y213617D01*
Y210507D01*
G01X730703Y228448D02*
X726656D01*
G01X730712Y228457D02*
X730703Y228448D01*
G01X725009Y213292D02*
X728595Y216878D01*
Y226340D01*
X730703Y228448D01*
G01X725009Y213292D02*
X723092Y211375D01*
Y208203D01*
X723570Y207725D01*
Y201626D01*
X725196Y200000D01*
G01X739852Y195915D02*
X736137Y192200D01*
X732996D01*
X731496Y193700D01*
G01Y196850D02*
X732450D01*
X734100Y198500D01*
X735196D01*
X737832Y201136D01*
Y202664D01*
G01X753580Y197200D02*
Y201700D01*
G01X737832Y202664D02*
X739068Y203900D01*
X751380D01*
X753580Y201700D01*
G01X728346Y190551D02*
X729920Y188977D01*
G01X739752Y199615D02*
X738315D01*
X735550Y196850D01*
X734645D01*
G01Y190551D02*
X738416D01*
G01X728346Y184252D02*
X729920Y182678D01*
G01X731496Y187401D02*
X732958Y185939D01*
X740901D01*
X741375Y185465D01*
X744436D01*
X748644Y189673D01*
Y191051D01*
G01X745485Y197673D02*
X748644Y194514D01*
Y191051D01*
G01X745485Y201673D02*
X741712Y197900D01*
X738845D01*
X734645Y193700D01*
G01X740352Y180115D02*
X735632D01*
X734645Y181102D01*
G01X728346Y187401D02*
X729920Y185827D01*
G01X724776Y209963D02*
Y206320D01*
X726546Y204550D01*
Y198200D01*
X725196Y196850D01*
G01X734286Y220973D02*
Y219473D01*
X724776Y209963D01*
G01X743752Y187115D02*
X743466Y187401D01*
X734645D01*
G01X731496Y184252D02*
X733183Y182565D01*
X739636D01*
X739786Y182715D01*
X742502D01*
G01X753568Y187253D02*
X752490D01*
X742252Y177015D01*
G01X731496Y177952D02*
X733148Y176300D01*
X741537D01*
X742252Y177015D01*
G01X734645Y177952D02*
X737315D01*
G01X733070Y179527D02*
X731496Y181101D01*
Y181102D01*
G01X720819Y209800D02*
X722047Y208572D01*
Y203149D01*
G01X738786Y228473D02*
Y227666D01*
X737375Y226255D01*
Y223075D01*
X739500Y220950D01*
G01X729246Y209941D02*
Y210696D01*
X739500Y220950D01*
G01X728346Y203149D02*
Y204594D01*
X727402Y205538D01*
Y207505D01*
X729246Y209349D01*
Y209941D01*
G01X753580Y210200D02*
X738340D01*
X736321Y208181D01*
X736272D01*
G01D02*
Y208132D01*
X734671Y206531D01*
Y202247D01*
X733100Y200676D01*
Y199553D01*
X732047Y198500D01*
X729996D01*
X728346Y196850D01*
G01X729136Y206654D02*
Y205556D01*
X729796Y204896D01*
Y202396D01*
X728346Y200946D01*
Y200000D01*
G01X729136Y206654D02*
X730896Y208414D01*
Y209960D01*
X734784Y213848D01*
X736498D01*
X743600Y220950D01*
G01X734645Y200000D02*
X735671Y201026D01*
Y202912D01*
X738839Y206080D01*
G01D02*
X738959Y206200D01*
X753580D01*
G01X731496Y200000D02*
Y201098D01*
X733565Y203167D01*
Y210184D01*
G01D02*
X735791Y212410D01*
X747407D01*
X749197Y214200D01*
X753580D01*
G01X728346Y193700D02*
X729920Y192126D01*
G01X720357Y207104D02*
X720643Y206818D01*
Y201404D01*
X722047Y200000D01*
G01X712598Y196850D02*
X714173Y198425D01*
G01X712720Y229666D02*
Y226460D01*
X704000Y217740D01*
Y214000D01*
X703477Y213477D01*
Y206695D01*
X701350Y204568D01*
Y201387D01*
X700000Y200037D01*
Y200000D01*
G01X712720Y234372D02*
Y229666D01*
G01X728346Y181102D02*
X729921Y179527D01*
G01X718897Y196850D02*
X720471Y198424D01*
G01X731915Y206310D02*
X731496Y205891D01*
Y203149D01*
G01X728346Y177952D02*
X729920Y176378D01*
G01X738952Y184215D02*
X738915Y184252D01*
X734645D01*
G01X744052Y193784D02*
X739168Y188900D01*
X733167D01*
X731516Y190551D01*
X731496D01*
G01X700000Y196850D02*
X701574Y198424D01*
G01X709448Y196850D02*
X711023Y198425D01*
G01X703149Y196850D02*
X704724Y198425D01*
G01X717322D02*
X715748Y196851D01*
Y196850D01*
G01X706299D02*
X707873Y198424D01*
G01X722047Y196850D02*
X723621Y198424D01*
G01X704724Y201574D02*
X703150Y200000D01*
X703149D01*
G01X706737Y205505D02*
X707852Y204390D01*
Y201553D01*
X706299Y200000D01*
G01X705336Y208437D02*
X704527Y207628D01*
Y204921D01*
X706299Y203149D01*
G01X711310Y207023D02*
Y205030D01*
X711100Y204820D01*
Y201652D01*
X709448Y200000D01*
G01X711750Y217500D02*
X707000D01*
G01D02*
Y209948D01*
X709448Y207500D01*
Y203149D01*
G01X715748D02*
X714173Y201574D01*
G01X718330Y205172D02*
X718897Y204605D01*
Y203149D01*
G01X759651Y266857D02*
X757337Y269171D01*
Y271913D01*
G01X762337Y278194D02*
X759212D01*
X757337Y276319D01*
Y271913D01*
G01X747220Y301620D02*
Y297120D01*
G01X753560Y273780D02*
Y265940D01*
X756143Y263357D01*
X759651D01*
G01X763292Y287630D02*
X759300D01*
X758065Y286395D01*
Y283156D01*
X759087Y282134D01*
X762337D01*
G01X757483Y305724D02*
X755574D01*
X754220Y304370D01*
X749970D01*
X747220Y301620D01*
G01X765018Y303671D02*
X761639D01*
X759586Y305724D01*
X757483D01*
G01X751470Y307270D02*
X752120D01*
X755774Y310924D01*
X757483D01*
G01X746970Y307270D02*
X751470D01*
G01X757483Y310924D02*
X759866D01*
X760518Y310272D01*
Y307889D01*
X762176Y306231D01*
X765018D01*
G01X757633Y321684D02*
Y317184D01*
G01X763505Y316008D02*
X762329Y317184D01*
X757633D01*
G01X715975Y429970D02*
X709765Y423760D01*
X704475D01*
X701325Y420610D01*
G01X710200Y434480D02*
X706120D01*
G01X714400Y442500D02*
X713100Y441200D01*
Y437380D01*
X710200Y434480D01*
G01X719850Y437470D02*
X714820Y442500D01*
X714400D01*
G01X739680Y423900D02*
X741600D01*
X743160Y425460D01*
Y428240D01*
G01D02*
Y429830D01*
X743480Y430150D01*
Y432140D01*
G01X737915Y433840D02*
Y429525D01*
X738320Y429120D01*
Y428730D01*
X739070Y427980D01*
G01D02*
Y424510D01*
X739680Y423900D01*
G01X724340Y447430D02*
Y443410D01*
G01X715975Y429970D02*
X718725Y432720D01*
X719443D01*
X724340Y437617D01*
Y443410D01*
G01X788287Y86087D02*
X786711Y84511D01*
X784767D01*
G01X765615Y157200D02*
X770100D01*
X786350Y173450D01*
Y178950D01*
X786400Y179000D01*
G01X779200Y178650D02*
X777050Y176500D01*
X770351D01*
G01X783390Y286000D02*
Y293180D01*
G01Y286000D02*
Y285999D01*
X786006Y283383D01*
G01X779890Y289000D02*
Y293180D01*
G01X771537Y284104D02*
X774444D01*
X775840Y285500D01*
X778500D01*
X779890Y286890D01*
Y289000D01*
G01X775486Y293180D02*
Y287316D01*
G01X762337Y284104D02*
X766477D01*
X767532Y285159D01*
Y289746D01*
G01D02*
Y292386D01*
X768326Y293180D01*
X771986D01*
G01X763840Y271430D02*
Y266760D01*
G01X771537Y278194D02*
X767341D01*
X763840Y274693D01*
Y271430D01*
G01X793837Y287696D02*
X801934D01*
G01X767890Y273380D02*
Y267310D01*
X763840Y263260D01*
G01X776518Y246482D02*
X770936Y252064D01*
Y254492D01*
X763840Y261588D01*
Y263260D01*
G01X759651Y263357D02*
Y258720D01*
X760766Y257605D01*
X762077D01*
X763788Y255894D01*
Y254868D01*
X767663Y250993D01*
G01X798220Y307120D02*
X800568D01*
X801728Y305960D01*
Y304572D01*
G01X801853Y300515D02*
X799748Y302620D01*
X798220D01*
G01X765018Y308791D02*
Y314495D01*
X763505Y316008D01*
G01X773000Y315800D02*
Y310400D01*
X777169Y306231D01*
X781198D01*
G01X794720Y307120D02*
X793267D01*
X792482Y306335D01*
X789597D01*
G01X781198Y303671D02*
X784351D01*
X787015Y306335D01*
X789597D01*
G01X781198Y301111D02*
X789658D01*
G01D02*
X791885D01*
X793394Y302620D01*
X794720D01*
G01X771520Y338394D02*
X771522Y338392D01*
X776497D01*
G01X781520Y350206D02*
X781518Y350204D01*
X775672D01*
G01X786560Y328180D02*
X782840D01*
X782800Y328220D01*
G01X791520Y327000D02*
Y338394D01*
G01X786560Y328180D02*
X788320D01*
X789500Y327000D01*
X791520D01*
G54D15*
X31000Y165500D03*
X29600Y227500D03*
Y223500D03*
X30400Y283200D03*
Y296700D03*
X44900Y261900D03*
X30700Y323000D03*
Y309500D03*
X77200Y314000D03*
X68750Y367751D03*
X26050Y367552D03*
X47100Y367400D03*
X87500Y217900D03*
X89000Y190900D03*
X77496Y281695D03*
Y276695D03*
Y286695D03*
X77400Y309500D03*
Y304500D03*
X89845Y367626D03*
X163970Y104310D03*
X187000Y110000D03*
X179500D03*
X163500Y109050D03*
X173500Y114500D03*
X196813Y114644D03*
X233700Y68000D03*
X231200Y73000D03*
X203700Y298800D03*
Y306800D03*
X257891Y371827D03*
X263200Y412100D03*
Y420300D03*
X259450Y426500D03*
X277700Y42500D03*
Y38000D03*
Y33500D03*
Y29000D03*
X286941Y278576D03*
X301410Y281122D03*
X281906Y297434D03*
X294900Y321700D03*
X372500Y288000D03*
X366200Y299200D03*
X374200D03*
Y340500D03*
X366200Y303200D03*
X374200D03*
X345091Y319717D03*
X345100Y323900D03*
X332386Y443510D03*
X433914Y356373D03*
X481700Y362400D03*
X477600Y350800D03*
X481700Y366800D03*
X625700Y162500D03*
X600737Y280017D03*
X625200Y278745D03*
X630528Y364424D03*
Y385304D03*
X601040Y395220D03*
X612350D03*
X629770Y468430D03*
X629323Y477831D03*
X594400Y479100D03*
X595390Y430440D03*
X668381Y400183D03*
X685800Y440950D03*
X686700Y433300D03*
X754400Y97800D03*
X757030Y201700D03*
Y214200D03*
Y210200D03*
X757583Y321684D03*
X750670Y301620D03*
X735442Y447367D03*
X727790Y447430D03*
X718050Y446230D03*
X766000Y164200D03*
X775436Y293180D03*
X783340D03*
G54D117*
X780495Y517441D03*
G54D24*
X41700Y127935D03*
G54D51*
X77257Y392835D03*
Y395395D03*
Y397955D03*
X70757D03*
Y392835D03*
X36850Y398560D03*
Y396000D03*
Y393440D03*
X43350D03*
Y398560D03*
G54D42*
X44850Y202810D03*
Y216590D03*
X64950D03*
Y202810D03*
G54D108*
X690890Y419020D03*
X687015Y411520D03*
X694765D03*
X701325Y420610D03*
X709075D03*
X734040Y441340D03*
X730165Y433840D03*
X737915D03*
X719850Y437470D03*
X715975Y429970D03*
X723725D03*
X705200Y428110D03*
G54D60*
X94488Y464075D03*
X102362D03*
X110236D03*
X118110D03*
X125984D03*
X133858D03*
X94488Y480807D03*
X102362D03*
X110236D03*
X118110D03*
X125984D03*
X133858D03*
X141732Y464075D03*
Y480807D03*
G54D33*
X38502Y161319D03*
X49302D03*
X43902D03*
X49302Y150519D03*
Y155919D03*
X43902Y150519D03*
Y155919D03*
X38502D03*
Y150519D03*
X108672Y138471D03*
Y132871D03*
X90672Y138471D03*
X102672D03*
X96672D03*
X84672D03*
Y132871D03*
X96672D03*
X102672D03*
X90672D03*
G54D127*
G01X509843Y214567D02*
X510986D01*
G02X511436Y214117I0J-450D01*
G01Y213437D01*
G03X512536Y212337I1100J0D01*
G01X514694D01*
X516376Y211246D01*
X516730Y210699D01*
X516731Y210698D01*
X517086Y210150D01*
Y210148D01*
X517697Y209204D01*
X517446Y208035D01*
X517493Y207962D01*
G01X505906Y218504D02*
X507049D01*
G02X507499Y218054I0J-450D01*
G01Y217224D01*
G03X508619Y216104I1120J0D01*
G01X514939D01*
X518797Y213551D01*
X518804Y213546D01*
X518927Y212961D01*
X519000Y212914D01*
G01X509843Y218504D02*
X508699D01*
G03X508249Y218054I0J-450D01*
G01Y217224D01*
G03X508619Y216854I370J0D01*
G01X515165D01*
X519212Y214177D01*
X519800Y214302D01*
X519873Y214255D01*
G01X521145Y217785D02*
X521072Y217832D01*
X520986Y218155D01*
X518430Y219816D01*
X517367Y220041D01*
X512556D01*
G02X511436Y221161I0J1120D01*
G01Y221991D01*
G03X510986Y222441I-450J0D01*
G01X509843D01*
G01X505906Y226378D02*
X507049D01*
G02X507499Y225928I0J-450D01*
G01Y225098D01*
G03X508619Y223978I1120J0D01*
G01X517799D01*
X518474Y223303D01*
X518561D01*
G01X509843Y226378D02*
X508699D01*
G03X508249Y225928I0J-450D01*
G01Y225098D01*
G03X508619Y224728I370J0D01*
G01X518299D01*
X518474Y224903D01*
X518561D01*
G01X509843Y230315D02*
X510986D01*
G02X511336Y229965I0J-350D01*
G01Y229455D01*
G03X511788Y228365I1540J0D01*
G03X512876Y227915I1088J1090D01*
G01X518582D01*
X519007Y227490D01*
X519094D01*
G01X518969Y231427D02*
X518882D01*
X518457Y231852D01*
X509025D01*
G02X507499Y233378I0J1526D01*
G01Y233802D01*
G03X507049Y234252I-450J0D01*
G01X505906D01*
G01X518969Y233027D02*
X518882D01*
X518457Y232602D01*
X509025D01*
G02X508249Y233378I0J776D01*
G01Y233802D01*
G02X508699Y234252I450J0D01*
G01X509843D01*
G01X520665Y236752D02*
X520578D01*
X520179Y237151D01*
X517623D01*
X516261Y235789D01*
X512556D01*
G02X511436Y236909I0J1120D01*
G01Y237739D01*
G03X510986Y238189I-450J0D01*
G01X509843D01*
G01X505906Y297245D02*
X507149D01*
G03X507499Y297595I0J350D01*
G01Y298113D01*
G02X507947Y299197I1533J1D01*
G02X509031Y299645I1083J-1085D01*
G01X514407D01*
X514922Y300160D01*
X516313D01*
X516590Y300437D01*
X516677D01*
G01X509843Y297245D02*
X508599D01*
G02X508249Y297595I0J350D01*
G01Y298113D01*
G02X508478Y298666I782J0D01*
G02X509031Y298895I553J-553D01*
G01X514718D01*
X515233Y299410D01*
X516017D01*
X516590Y298837D01*
X516677D01*
G01X505906Y289371D02*
X507149D01*
G03X507499Y289721I0J350D01*
G01Y290372D01*
G02X507908Y291362I1400J1D01*
G02X508898Y291771I989J-991D01*
G01X518839D01*
X519117Y292049D01*
X519204D01*
G01X509843Y289371D02*
X508599D01*
G02X508249Y289721I0J350D01*
G01Y290372D01*
G02X508439Y290831I649J0D01*
G02X508898Y291021I459J-459D01*
G01X518545D01*
X519117Y290449D01*
X519204D01*
G01X518605Y295912D02*
X518518D01*
X518314Y295708D01*
X512802D01*
G03X511837Y295309I0J-1366D01*
G03X511436Y294341I968J-968D01*
G01Y293658D01*
G02X511086Y293308I-350J0D01*
G01X509843D01*
G01X515215Y303948D02*
X515128D01*
X514762Y303582D01*
X512992D01*
G03X511891Y303127I-1J-1557D01*
G03X511436Y302026I1102J-1100D01*
G01Y301532D01*
G02X511086Y301182I-350J0D01*
G01X509843D01*
G01X513780Y214567D02*
X512636D01*
G03X512186Y214117I0J-450D01*
G01Y213437D01*
G03X512536Y213087I350J0D01*
G01X514917D01*
X516919Y211788D01*
X518784Y208908D01*
X518788Y208907D01*
X518835Y208834D01*
G01X522017Y219127D02*
X521944Y219174D01*
X521079Y218991D01*
X518722Y220521D01*
X517450Y220791D01*
X512556D01*
G02X512186Y221161I0J370D01*
G01Y221991D01*
G02X512636Y222441I450J0D01*
G01X513780D01*
G01Y230315D02*
X512636D01*
G03X512086Y229765I0J-550D01*
G01Y229455D01*
G03X512318Y228896I789J0D01*
G03X512876Y228665I558J558D01*
G01X518582D01*
X519007Y229090D01*
X519094D01*
G01X520665Y238352D02*
X520578D01*
X520127Y237901D01*
X517312D01*
X515950Y236539D01*
X512556D01*
G02X512186Y236909I0J370D01*
G01Y237739D01*
G02X512636Y238189I450J0D01*
G01X513780D01*
G01X518605Y294312D02*
X518518D01*
X517872Y294958D01*
X512802D01*
G03X512367Y294778I0J-616D01*
G03X512186Y294341I437J-437D01*
G01Y293658D01*
G03X512536Y293308I350J0D01*
G01X513780D01*
G01X515215Y302348D02*
X515128D01*
X514644Y302832D01*
X512992D01*
G03X512422Y302596I0J-806D01*
G03X512186Y302026I570J-570D01*
G01Y301532D01*
G03X512536Y301182I350J0D01*
G01X513780D01*
G54D16*
X27600Y165500D03*
X26200Y227500D03*
Y223500D03*
X74096Y281695D03*
Y276695D03*
Y286695D03*
X27000Y283200D03*
Y296700D03*
X41500Y261900D03*
X27300Y323000D03*
Y309500D03*
X73800Y314000D03*
X74000Y309500D03*
Y304500D03*
X65350Y367751D03*
X22650Y367552D03*
X43700Y367400D03*
X84100Y217900D03*
X85600Y190900D03*
X86445Y367626D03*
X160570Y104310D03*
X183600Y110000D03*
X176100D03*
X160100Y109050D03*
X170100Y114500D03*
X193413Y114644D03*
X200300Y298800D03*
Y306800D03*
X230300Y68000D03*
X227800Y73000D03*
X254491Y371827D03*
X259800Y412100D03*
Y420300D03*
X256050Y426500D03*
X274300Y42500D03*
Y38000D03*
Y33500D03*
Y29000D03*
X283541Y278576D03*
X298010Y281122D03*
X278506Y297434D03*
X291500Y321700D03*
X369100Y288000D03*
X362800Y299200D03*
X370800D03*
Y340500D03*
X362800Y303200D03*
X370800D03*
X341691Y319717D03*
X341700Y323900D03*
X328986Y443510D03*
X430514Y356373D03*
X478300Y362400D03*
X474200Y350800D03*
X478300Y366800D03*
X622300Y162500D03*
X597337Y280017D03*
X621800Y278745D03*
X627128Y364424D03*
Y385304D03*
X597640Y395220D03*
X608950D03*
X626370Y468430D03*
X625923Y477831D03*
X591000Y479100D03*
X591990Y430440D03*
X664981Y400183D03*
X682400Y440950D03*
X683300Y433300D03*
X751000Y97800D03*
X753630Y201700D03*
Y214200D03*
Y210200D03*
X754183Y321684D03*
X747270Y301620D03*
X732042Y447367D03*
X724390Y447430D03*
X714650Y446230D03*
X762600Y164200D03*
X772036Y293180D03*
X779940D03*
G54D52*
X69300Y372000D03*
X26100Y371552D03*
X46900Y371433D03*
X89895Y371626D03*
X164810Y143631D03*
X189413Y114544D03*
X279000Y405700D03*
X348597Y217040D03*
X337900Y424200D03*
X598152Y362741D03*
X598023Y386411D03*
X690500Y382000D03*
X683781Y392333D03*
X701120Y433820D03*
X797155Y293467D03*
X805300Y267200D03*
G54D34*
X56541Y231086D03*
X75500Y231100D03*
X33700Y223500D03*
X76800Y183200D03*
X29900Y203600D03*
X70500Y231100D03*
X52400D03*
X32405Y184317D03*
X36405D03*
X30700Y275500D03*
X31400Y301800D03*
X25700Y388500D03*
X77200Y367100D03*
X38200Y366900D03*
X34100D03*
X60400Y366700D03*
X54800D03*
X25700Y396000D03*
X37500Y384000D03*
X85700Y183400D03*
X91300Y223700D03*
X93700Y391200D03*
X81300Y367100D03*
X98295Y366893D03*
X102395D03*
X246530Y66836D03*
X252000Y284500D03*
X230700D03*
X256000D03*
X234800Y284400D03*
X215300Y284000D03*
X271600Y284500D03*
X275600D03*
X294708Y292126D03*
X287214Y288217D03*
X323900Y247800D03*
X265250Y370750D03*
X279000Y398300D03*
X348597Y209640D03*
X365387Y258009D03*
X372119Y257880D03*
X384000Y341050D03*
X330531Y409161D03*
X416841Y340384D03*
X447300Y340800D03*
X472296D03*
X506200Y352300D03*
X499700D03*
X493200D03*
X476500Y340800D03*
X532894Y347615D03*
X528894D03*
X535336Y331822D03*
X541714Y331803D03*
X547315Y331788D03*
X551394D03*
X518000Y351450D03*
X514000Y351600D03*
X613211Y280205D03*
X608711D03*
X617000Y472800D03*
X621500D03*
X667353Y226932D03*
X641579Y227190D03*
X658610Y226975D03*
X663110D03*
X654464Y227115D03*
X650287Y227074D03*
X645968Y227097D03*
X691100Y233800D03*
X686900D03*
X678500D03*
X654770Y394660D03*
X658840D03*
X687581Y392433D03*
X686390Y424870D03*
X695380Y424850D03*
X731900Y88600D03*
X730712Y228507D03*
X738786Y228523D03*
X725750Y217572D03*
X712720Y234422D03*
X746970Y307320D03*
X700200Y391300D03*
X710200Y434530D03*
X717150Y450295D03*
X706120Y434530D03*
X743480Y432190D03*
X801934Y287746D03*
G54D25*
X76600Y134220D03*
Y120380D03*
G54D109*
X673211Y371204D03*
Y367267D03*
X662695Y369236D03*
G54D118*
X765018Y301111D03*
Y303671D03*
Y306231D03*
Y308791D03*
X781198D03*
Y306231D03*
Y303671D03*
Y301111D03*
G54D43*
X45150Y204779D03*
Y206747D03*
Y208716D03*
Y210684D03*
Y212653D03*
Y214621D03*
X64650D03*
Y212653D03*
Y210684D03*
Y208716D03*
Y206747D03*
Y204779D03*
G54D70*
X177800Y131500D03*
G54D61*
X158267Y25708D03*
X145669D03*
X158267Y47362D03*
X145669D03*
G54D128*
G01X411417Y222441D02*
X409449Y220473D01*
G01X411417Y218504D02*
X409449Y216536D01*
G01X415354Y222441D02*
X413386Y220473D01*
G01X415354Y218504D02*
X413386Y216536D01*
G01X419291Y222441D02*
X417323Y220473D01*
G01X419291Y218504D02*
X417323Y216536D01*
G01X423228Y222441D02*
X421260Y220473D01*
G01X423228Y218504D02*
X421260Y216536D01*
G01X427165Y222441D02*
X425197Y220473D01*
G01X427165Y218504D02*
X425197Y216536D01*
G01X431102Y222441D02*
X429134Y220473D01*
G01X431102Y218504D02*
X429134Y216536D01*
G01X435039Y222441D02*
X433071Y220473D01*
G01X435039Y218504D02*
X433071Y216536D01*
G01X438976Y222441D02*
X437008Y220473D01*
G01X438976Y218504D02*
X437008Y216536D01*
G01X442913Y222441D02*
X440945Y220473D01*
G01X442913Y218504D02*
X440945Y216536D01*
G01X446850Y222441D02*
X444882Y220473D01*
G01X446850Y218504D02*
X444882Y216536D01*
G01X450787Y222441D02*
X448819Y220473D01*
G01X450787Y218504D02*
X448819Y216536D01*
G01X411417Y206693D02*
X409449Y204725D01*
G01X411417Y202756D02*
X409449Y200788D01*
G01X415354Y210630D02*
X413386Y208662D01*
G01X415354Y206693D02*
X413386Y204725D01*
G01X419291Y206693D02*
X417323Y204725D01*
G01X419291Y202756D02*
X417323Y200788D01*
G01X423228Y210630D02*
X421260Y208662D01*
G01X423228Y206693D02*
X421260Y204725D01*
G01X427165Y206693D02*
X425197Y204725D01*
G01X427165Y202756D02*
X425197Y200788D01*
G01X431102Y210630D02*
X429134Y208662D01*
G01X431102Y206693D02*
X429134Y204725D01*
G01X435039Y206693D02*
X433071Y204725D01*
G01X435039Y202756D02*
X433071Y200788D01*
G01X438976Y210630D02*
X437008Y208662D01*
G01X438976Y206693D02*
X437008Y204725D01*
G01X442913Y206693D02*
X440945Y204725D01*
G01X442913Y202756D02*
X440945Y200788D01*
G01X446850Y210630D02*
X444882Y208662D01*
G01X446850Y206693D02*
X444882Y204725D01*
G01X450787Y206693D02*
X448819Y204725D01*
G01X450787Y202756D02*
X448819Y200788D01*
G01X391732Y218504D02*
X389764Y216536D01*
G01X391732Y214567D02*
X389764Y212599D01*
G01X399606Y222441D02*
X397638Y220473D01*
G01X399606Y218504D02*
X397638Y216536D01*
G01X403543Y222441D02*
X401575Y220473D01*
G01X403543Y218504D02*
X401575Y216536D01*
G01X407480Y222441D02*
X405512Y220473D01*
G01X407480Y218504D02*
X405512Y216536D01*
G01X395669Y206693D02*
X393701Y204725D01*
G01X395669Y202756D02*
X393701Y200788D01*
G01X399606Y210630D02*
X397638Y208662D01*
G01X399606Y206693D02*
X397638Y204725D01*
G01X403543Y206693D02*
X401575Y204725D01*
G01X403543Y202756D02*
X401575Y200788D01*
G01X407480Y210630D02*
X405512Y208662D01*
G01X407480Y206693D02*
X405512Y204725D01*
G01X454725Y222441D02*
X456693Y220473D01*
G01X454725Y218504D02*
X456693Y216536D01*
G01X458662Y222441D02*
X460630Y220473D01*
G01X458662Y218504D02*
X460630Y216536D01*
G01X462599Y222441D02*
X464567Y220473D01*
G01X462599Y218504D02*
X464567Y216536D01*
G01X466536Y222441D02*
X468504Y220473D01*
G01X466536Y218504D02*
X468504Y216536D01*
G01X470473Y222441D02*
X472441Y220473D01*
G01X470473Y218504D02*
X472441Y216536D01*
G01X474410Y222441D02*
X476378Y220473D01*
G01X474410Y218504D02*
X476378Y216536D01*
G01X478347Y222441D02*
X480315Y220473D01*
G01X478347Y218504D02*
X480315Y216536D01*
G01X482284Y222441D02*
X484252Y220473D01*
G01X482284Y218504D02*
X484252Y216536D01*
G01X486221Y222441D02*
X488189Y220473D01*
G01X486221Y218504D02*
X488189Y216536D01*
G01X498032Y210630D02*
X500000Y208662D01*
G01X501969Y210630D02*
X503937Y208662D01*
G01X494095Y214567D02*
X496063Y212599D01*
G01X498032Y214567D02*
X500000Y212599D01*
G01X494095Y218504D02*
X496063Y216536D01*
G01X498032Y218504D02*
X500000Y216536D01*
G01X494095Y222441D02*
X496063Y220473D01*
G01X498032Y222441D02*
X500000Y220473D01*
G01X494095Y226378D02*
X496063Y224410D01*
G01X498032Y226378D02*
X500000Y224410D01*
G01X494095Y230315D02*
X496063Y228347D01*
G01X498032Y230315D02*
X500000Y228347D01*
G01X494095Y234252D02*
X496063Y232284D01*
G01X498032Y234252D02*
X500000Y232284D01*
G01X494095Y238189D02*
X496063Y236221D01*
G01X498032Y238189D02*
X500000Y236221D01*
G01X454725Y210630D02*
X456693Y208662D01*
G01X454725Y206693D02*
X456693Y204725D01*
G01X458662Y206693D02*
X460630Y204725D01*
G01X458662Y202756D02*
X460630Y200788D01*
G01X462599Y210630D02*
X464567Y208662D01*
G01X462599Y206693D02*
X464567Y204725D01*
G01X466536Y206693D02*
X468504Y204725D01*
G01X466536Y202756D02*
X468504Y200788D01*
G01X470473Y210630D02*
X472441Y208662D01*
G01X470473Y206693D02*
X472441Y204725D01*
G01X474410Y206693D02*
X476378Y204725D01*
G01X474410Y202756D02*
X476378Y200788D01*
G01X478347Y210630D02*
X480315Y208662D01*
G01X478347Y206693D02*
X480315Y204725D01*
G01X482284Y206693D02*
X484252Y204725D01*
G01X482284Y202756D02*
X484252Y200788D01*
G01X486221Y210630D02*
X488189Y208662D01*
G01X486221Y206693D02*
X488189Y204725D01*
G01X494095Y257874D02*
X496063Y255906D01*
G01X498032Y257874D02*
X500000Y255906D01*
G01X494095Y261811D02*
X496063Y259843D01*
G01X498032Y261811D02*
X500000Y259843D01*
G01X494095Y265749D02*
X496063Y267717D01*
G01X498032Y265749D02*
X500000Y267717D01*
G01X494095Y242126D02*
X496063Y240158D01*
G01X498032Y242126D02*
X500000Y240158D01*
G01X494095Y246063D02*
X496063Y244095D01*
G01X498032Y246063D02*
X500000Y244095D01*
G01X494095Y269686D02*
X496063Y271654D01*
G01X498032Y269686D02*
X500000Y271654D01*
G01X494095Y250000D02*
X496063Y248032D01*
G01X498032Y250000D02*
X500000Y248032D01*
G01X494095Y253937D02*
X496063Y251969D01*
G01X498032Y253937D02*
X500000Y251969D01*
G01X494095Y273623D02*
X496063Y275591D01*
G01X498032Y273623D02*
X500000Y275591D01*
G01X494095Y277560D02*
X496063Y279528D01*
G01X498032Y277560D02*
X500000Y279528D01*
G01X494095Y281497D02*
X496063Y283465D01*
G01X498032Y281497D02*
X500000Y283465D01*
G01X494095Y285434D02*
X496063Y287402D01*
G01X498032Y285434D02*
X500000Y287402D01*
G01X505906Y257874D02*
X507874Y255906D01*
G01X509843Y257874D02*
X511811Y255906D01*
G01X509843Y261811D02*
X511811Y259843D01*
G01X505906Y265749D02*
X507874Y267717D01*
G01X509843Y265749D02*
X511811Y267717D01*
G01X505906Y242126D02*
X507874Y240158D01*
G01X509843Y242126D02*
X511811Y240158D01*
G01X509843Y246063D02*
X511811Y244095D01*
G01X509843Y269686D02*
X511811Y271654D01*
G01X505906Y250000D02*
X507874Y248032D01*
G01X509843Y250000D02*
X511811Y248032D01*
G01X509843Y253937D02*
X511811Y251969D01*
G01X505906Y273623D02*
X507874Y275591D01*
G01X509843Y273623D02*
X511811Y275591D01*
G01X509843Y277560D02*
X511811Y279528D01*
G01X505906Y281497D02*
X507874Y283465D01*
G01X509843Y281497D02*
X511811Y283465D01*
G01X509843Y285434D02*
X511811Y287402D01*
G01X494095Y297245D02*
X496063Y299213D01*
G01X498032Y297245D02*
X500000Y299213D01*
G01X494095Y289371D02*
X496063Y291339D01*
G01X498032Y289371D02*
X500000Y291339D01*
G01X494095Y293308D02*
X496063Y295276D01*
G01X498032Y293308D02*
X500000Y295276D01*
G01X494095Y301182D02*
X496063Y303150D01*
G01X498032Y301182D02*
X500000Y303150D01*
G01X513780Y261811D02*
X515748Y259843D01*
G01X513780Y246063D02*
X515748Y244095D01*
G01X513780Y269686D02*
X515748Y271654D01*
G01X513780Y253937D02*
X515748Y251969D01*
G01X513780Y277560D02*
X515748Y279528D01*
G01X513780Y285434D02*
X515748Y287402D01*
G54D35*
X56541Y234486D03*
X75500Y234500D03*
X33700Y226900D03*
X76800Y186600D03*
X29900Y207000D03*
X70500Y234500D03*
X52400D03*
X32405Y187717D03*
X36405D03*
X30700Y278900D03*
X31400Y305200D03*
X25700Y391900D03*
X77200Y370500D03*
X38200Y370300D03*
X34100D03*
X60400Y370100D03*
X54800D03*
X25700Y399400D03*
X37500Y387400D03*
X85700Y186800D03*
X91300Y227100D03*
X93700Y394600D03*
X81300Y370500D03*
X98295Y370293D03*
X102395D03*
X246530Y70236D03*
X252000Y287900D03*
X230700D03*
X256000D03*
X234800Y287800D03*
X215300Y287400D03*
X271600Y287900D03*
X275600D03*
X294708Y295526D03*
X287214Y291617D03*
X323900Y251200D03*
X265250Y374150D03*
X279000Y401700D03*
X348597Y213040D03*
X365387Y261409D03*
X372119Y261280D03*
X384000Y344450D03*
X330531Y412561D03*
X416841Y343784D03*
X447300Y344200D03*
X472296D03*
X506200Y355700D03*
X499700D03*
X493200D03*
X476500Y344200D03*
X532894Y351015D03*
X528894D03*
X535336Y335222D03*
X541714Y335203D03*
X547315Y335188D03*
X551394D03*
X518000Y354850D03*
X514000Y355000D03*
X613211Y283605D03*
X608711D03*
X617000Y476200D03*
X621500D03*
X667353Y230332D03*
X641579Y230590D03*
X658610Y230375D03*
X663110D03*
X654464Y230515D03*
X650287Y230474D03*
X645968Y230497D03*
X691100Y237200D03*
X686900D03*
X678500D03*
X654770Y398060D03*
X658840D03*
X687581Y395833D03*
X686390Y428270D03*
X695380Y428250D03*
X731900Y92000D03*
X730712Y231907D03*
X738786Y231923D03*
X725750Y220972D03*
X712720Y237822D03*
X746970Y310720D03*
X700200Y394700D03*
X710200Y437930D03*
X717150Y453695D03*
X706120Y437930D03*
X743480Y435590D03*
X801934Y291146D03*
G54D17*
X56507Y175552D03*
X75400Y221000D03*
X34900Y211900D03*
X36249Y191548D03*
X50300Y190700D03*
X75400Y321700D03*
X74200Y338000D03*
X31500Y337800D03*
X52500Y337600D03*
X60900Y391050D03*
X60880Y399390D03*
X95295Y337793D03*
X181100Y114500D03*
X197013Y118544D03*
X204694Y209985D03*
X252645Y279732D03*
X211200Y287800D03*
X221800Y484000D03*
X279126Y278333D03*
X280700Y328400D03*
X354300Y347500D03*
X332508Y439668D03*
X539300Y418400D03*
X621800Y166500D03*
X600837Y284017D03*
X625300Y288745D03*
X597300Y334350D03*
X625300Y327654D03*
X597300Y337900D03*
X595470Y426720D03*
X590100Y490400D03*
X669083Y347018D03*
X671767Y396181D03*
X753908Y280164D03*
X731700Y463900D03*
X739120Y427980D03*
G54D53*
X69300Y375600D03*
X26100Y375152D03*
X46900Y375033D03*
X89895Y375226D03*
X164810Y147231D03*
X189413Y118144D03*
X279000Y409300D03*
X348597Y220640D03*
X337900Y427800D03*
X598152Y366341D03*
X598023Y390011D03*
X690500Y385600D03*
X683781Y395933D03*
X701120Y437420D03*
X797155Y297067D03*
X805300Y270800D03*
G54D119*
X777110Y386910D03*
G54D44*
X54900Y209700D03*
G54D26*
X33000Y159300D03*
Y151700D03*
X89433Y125588D03*
Y117988D03*
X104930Y125610D03*
Y118010D03*
X97230Y125620D03*
Y118020D03*
X153300Y174700D03*
Y167100D03*
X161300Y174700D03*
Y167100D03*
X169300Y174700D03*
Y167100D03*
X141200Y192000D03*
Y199600D03*
X148900Y192000D03*
Y199600D03*
X156700Y192000D03*
Y199600D03*
X172300Y192000D03*
Y199600D03*
X164400Y192000D03*
Y199600D03*
X210500Y206400D03*
Y198800D03*
X243300Y354900D03*
Y362500D03*
X239125Y481261D03*
X231125D03*
X247125D03*
X239125Y488861D03*
X231125D03*
X247125D03*
X560000Y392200D03*
Y399800D03*
X545206Y416682D03*
Y409082D03*
X553206Y416682D03*
Y409082D03*
X561706Y416682D03*
Y409082D03*
X626900Y441200D03*
Y433600D03*
X606000Y438800D03*
Y431200D03*
X635000Y433700D03*
Y441300D03*
X688200Y321700D03*
Y329300D03*
X696305Y329202D03*
Y321602D03*
X667617Y352167D03*
Y359767D03*
X646600Y372200D03*
Y364600D03*
X704805Y329202D03*
Y321602D03*
G54D80*
X261713Y386027D03*
X259744D03*
X257776D03*
X255807D03*
X253839D03*
X251870D03*
X249901D03*
X247933D03*
X245964D03*
X243996D03*
X242027D03*
Y405313D03*
X243996D03*
X245964D03*
X247933D03*
X249901D03*
X251870D03*
X253839D03*
X255807D03*
X257776D03*
X259744D03*
X261713D03*
G54D71*
X185789Y185500D03*
G54D62*
X158267Y53267D03*
Y41456D03*
Y31614D03*
Y19803D03*
X145669D03*
Y31614D03*
Y41456D03*
Y53267D03*
G54D129*
G01X261102Y77900D02*
Y75310D01*
G01X289161Y58068D02*
X288495D01*
X286998Y59565D01*
X283302D01*
G01X317700Y275400D02*
Y276292D01*
X318659Y277251D01*
X322650D01*
G01X318250Y262500D02*
X318831Y263081D01*
X322650D01*
G01Y278826D02*
X317626D01*
X317600Y278800D01*
G01X344850Y261506D02*
X340606D01*
X339500Y260400D01*
G01X634216Y25268D02*
X632206D01*
X629813Y27661D01*
G01X651391Y19913D02*
X649961Y21343D01*
Y25268D01*
G01X651564Y52638D02*
X649961Y51035D01*
Y47468D01*
G01X651181Y122834D02*
Y119775D01*
X651256Y119700D01*
Y116610D01*
X649606Y114960D01*
G01X692126Y125984D02*
X694614D01*
X695333Y125265D01*
Y122777D01*
X696850Y121260D01*
G01X703149Y193700D02*
X701549Y195300D01*
X698450D01*
X696850Y193700D01*
G01X725196Y121260D02*
X723682Y119746D01*
X720411D01*
X718897Y121260D01*
G54D18*
X52907Y175552D03*
X71800Y221000D03*
X31300Y211900D03*
X32649Y191548D03*
X46700Y190700D03*
X71800Y321700D03*
X70600Y338000D03*
X27900Y337800D03*
X48900Y337600D03*
X57300Y391050D03*
X57280Y399390D03*
X91695Y337793D03*
X177500Y114500D03*
X193413Y118544D03*
X201094Y209985D03*
X249045Y279732D03*
X207600Y287800D03*
X218200Y484000D03*
X275526Y278333D03*
X277100Y328400D03*
X350700Y347500D03*
X328908Y439668D03*
X535700Y418400D03*
X618200Y166500D03*
X597237Y284017D03*
X621700Y288745D03*
X593700Y334350D03*
X621700Y327654D03*
X593700Y337900D03*
X591870Y426720D03*
X586500Y490400D03*
X665483Y347018D03*
X668167Y396181D03*
X750308Y280164D03*
X728100Y463900D03*
X735520Y427980D03*
G54D63*
X149100Y136500D03*
X152700D03*
G54D54*
X46277Y517441D03*
G54D72*
X185789Y188000D03*
G54D27*
X33100Y171500D03*
X25500D03*
X34100Y217500D03*
X26500D03*
X63626Y250139D03*
X56026D03*
X183498Y145380D03*
X191098D03*
X236000Y362400D03*
X228400D03*
X236000Y370100D03*
X228400D03*
X236000Y377800D03*
X228400D03*
X234300Y394954D03*
X226700D03*
X223800Y478500D03*
X216200D03*
X223800Y470500D03*
X216200D03*
X281300Y147500D03*
X273700D03*
X281300Y156500D03*
X273700D03*
X281300Y239500D03*
X273700D03*
X281300Y198000D03*
X273700D03*
X281300Y231000D03*
X273700D03*
X281300Y189500D03*
X273700D03*
X540800Y423900D03*
X533200D03*
X540800Y431500D03*
X533200D03*
X647600Y354400D03*
X655200D03*
X647600Y346700D03*
X655200D03*
X647600Y339000D03*
X655200D03*
X647623Y331307D03*
X655223D03*
X647623Y323624D03*
X655223D03*
X695100Y483400D03*
X712598Y459729D03*
X720198D03*
X733700Y469400D03*
X726100D03*
X712100Y467900D03*
X719700D03*
X712034Y475600D03*
X719634D03*
X712034Y483400D03*
X719634D03*
X702700D03*
G54D81*
X236820Y417395D03*
Y439281D03*
G54D36*
X68400Y182100D03*
X81300Y182200D03*
X169800Y144200D03*
X208100Y162100D03*
X296500Y138700D03*
X297000Y222550D03*
X296500Y180500D03*
X283100Y418600D03*
X566500Y392700D03*
X624770Y455430D03*
X615870Y433930D03*
X620600Y433900D03*
X681900Y321800D03*
X681540Y419660D03*
X686300Y365500D03*
X672800Y442600D03*
G54D90*
X401575Y410039D03*
X410433D03*
X419292D03*
X404528Y412795D03*
X413386D03*
X422244D03*
X401575Y425000D03*
X410433D03*
X419292D03*
X407480Y422244D03*
X416339D03*
X425197D03*
X407480Y407284D03*
X416339D03*
X425197D03*
X404528Y427756D03*
X413386D03*
X422244D03*
X401575Y439961D03*
X410433D03*
X419292D03*
X404528Y442717D03*
X413386D03*
X422244D03*
X401575Y454921D03*
X410433D03*
X419292D03*
X404528Y457677D03*
X413386D03*
X422244D03*
X407480Y437205D03*
X416339D03*
X425197D03*
X407480Y452165D03*
X416339D03*
X425197D03*
G54D45*
X54900Y204700D03*
X49900Y209700D03*
X59900D03*
X54900Y214700D03*
Y209700D03*
X201400Y174400D03*
X192400D03*
X196900D03*
X179800Y133500D03*
X175800Y129500D03*
X179800D03*
X175800Y133500D03*
X192400Y191600D03*
X196900D03*
X201400D03*
X192400Y187300D03*
X196900D03*
X201400D03*
Y178700D03*
X192400Y183000D03*
X196900D03*
X201400D03*
X192400Y178700D03*
X196900D03*
X246493Y399567D03*
X242893D03*
X257020Y390670D03*
X253420D03*
X249820D03*
X246220D03*
X256120Y395170D03*
X243120D03*
X247620D03*
X251870D03*
X242620Y390670D03*
X260893Y399567D03*
X257293D03*
X260620Y390670D03*
Y395170D03*
X253693Y399567D03*
X250093D03*
X609400Y446850D03*
X604400Y456100D03*
Y451850D03*
Y447350D03*
Y460350D03*
X609400Y450450D03*
Y454050D03*
Y457650D03*
Y461250D03*
X599503Y447123D03*
Y450723D03*
Y454323D03*
Y457923D03*
X604400Y464850D03*
X609400D03*
X599503Y461523D03*
Y465123D03*
X694400Y452900D03*
Y457400D03*
Y461900D03*
X689900Y457400D03*
Y452950D03*
X689700Y461850D03*
X698900Y457400D03*
X699000Y452950D03*
X698950Y461800D03*
G54D28*
X43487Y166781D03*
X39612Y174281D03*
X47362D03*
X656500Y63250D03*
X660375Y70750D03*
X652625D03*
G54D73*
X223549Y81399D03*
X226109D03*
X228669D03*
Y87899D03*
X223549D03*
X243049Y81399D03*
X245609D03*
X248169D03*
Y87899D03*
X243049D03*
X292378Y304389D03*
X294938D03*
X297498D03*
Y310889D03*
X292378D03*
X279378Y304389D03*
X281938D03*
X284498D03*
Y310889D03*
X279378D03*
X327365Y422661D03*
X332485D03*
Y429161D03*
X329925D03*
X327365D03*
X670494Y425456D03*
X675614D03*
Y431956D03*
X673054D03*
X670494D03*
G54D82*
X289500Y136500D03*
Y147500D03*
Y167500D03*
Y156500D03*
Y239500D03*
Y209000D03*
Y198000D03*
Y178500D03*
Y189500D03*
Y220000D03*
Y231000D03*
Y250500D03*
X573500Y401500D03*
Y390500D03*
G54D64*
X185789Y175500D03*
Y180500D03*
X208011Y175500D03*
Y190500D03*
Y185500D03*
Y180500D03*
G54D91*
X496499Y175070D03*
X494199D03*
X506245Y175012D03*
X503945D03*
X496499Y177270D03*
X494199D03*
X506245Y177212D03*
X503945D03*
X516370Y174954D03*
X514070D03*
X526495Y174896D03*
X524195D03*
X516370Y177154D03*
X514070D03*
X526495Y177096D03*
X524195D03*
G54D37*
X68400Y187700D03*
X81300Y187800D03*
X169800Y149800D03*
X208100Y167700D03*
X296500Y144300D03*
X297000Y228150D03*
X296500Y186100D03*
X283100Y424200D03*
X566500Y398300D03*
X624770Y461030D03*
X615870Y439530D03*
X620600Y439500D03*
X681900Y327400D03*
X686300Y371100D03*
X672800Y448200D03*
X681540Y425260D03*
G54D19*
X26500Y160300D03*
X49700Y398200D03*
X242733Y70311D03*
X223995Y70291D03*
X226200Y408200D03*
X275500Y409300D03*
X344891Y209640D03*
X691400Y394700D03*
X652200Y370100D03*
X757488Y301161D03*
X713150Y453795D03*
X778440Y282210D03*
X786560Y328230D03*
G54D46*
X74100Y291700D03*
X71800Y318200D03*
X46700Y387500D03*
X95850Y452650D03*
X222200Y95000D03*
X241700D03*
X239000Y279700D03*
X231800Y316900D03*
X250175Y316967D03*
X214400Y317000D03*
X269565Y317151D03*
X291300Y328300D03*
X356500Y334000D03*
X626200Y166500D03*
X629200Y299091D03*
Y288745D03*
Y337500D03*
Y327654D03*
X622770Y369320D03*
X623470Y389940D03*
X586550Y482900D03*
X595700Y434500D03*
X689935Y441196D03*
X714100Y489400D03*
G54D55*
X37402Y499724D03*
X789370D03*
G54D38*
X59800Y188700D03*
X82600Y228300D03*
X176500Y175400D03*
X178500Y198800D03*
X297000Y164800D03*
X296500Y205900D03*
Y247950D03*
X569070Y466030D03*
X581000Y398300D03*
X695700Y395850D03*
X647623Y384089D03*
X642907D03*
X715800Y387400D03*
X736400Y462200D03*
G54D29*
X66403Y140952D03*
X59997D03*
G54D92*
X571249Y127362D03*
X573401Y127820D03*
X570771Y129612D03*
X572923Y130070D03*
X584086Y174012D03*
X586238Y174470D03*
X579993Y158187D03*
X582145Y158645D03*
X579515Y160436D03*
X581667Y160894D03*
X589314Y149359D03*
X591466Y149817D03*
X588836Y151608D03*
X590988Y152066D03*
X582353Y138181D03*
X584505Y138639D03*
X581875Y140430D03*
X584027Y140888D03*
X583321Y214047D03*
X585473Y214505D03*
X582842Y216296D03*
X584994Y216754D03*
X579391Y198464D03*
X581543Y198922D03*
X578913Y200713D03*
X581065Y201171D03*
X575189Y182722D03*
X577341Y183180D03*
X574711Y184971D03*
X576863Y185429D03*
X583608Y176262D03*
X585760Y176720D03*
G54D65*
X196900Y183000D03*
G54D83*
X272268Y395524D03*
G54D56*
X37402Y535158D03*
X789370D03*
G54D47*
X28150Y265800D03*
X35650Y261925D03*
Y269675D03*
G54D74*
X261102Y75310D03*
Y73735D03*
Y72160D03*
Y70585D03*
Y69010D03*
Y67435D03*
Y65865D03*
Y64290D03*
Y62715D03*
Y61140D03*
Y59565D03*
Y57990D03*
X283302D03*
Y59565D03*
Y61140D03*
Y62715D03*
Y64290D03*
Y65865D03*
Y67435D03*
Y69010D03*
Y70585D03*
Y72160D03*
Y73735D03*
Y75310D03*
X322650Y278826D03*
Y277251D03*
Y275676D03*
Y274101D03*
Y272526D03*
Y270951D03*
Y269381D03*
Y267806D03*
Y266231D03*
Y264656D03*
Y263081D03*
Y261506D03*
X344850D03*
Y263081D03*
Y264656D03*
Y266231D03*
Y267806D03*
Y269381D03*
Y270951D03*
Y272526D03*
Y274101D03*
Y275676D03*
Y277251D03*
Y278826D03*
G54D66*
X193264Y138648D03*
X605570Y475480D03*
G54D84*
X269768Y395524D03*
G54D75*
X235500Y147500D03*
X260300D03*
X234750Y238600D03*
X259550D03*
X234700Y213500D03*
X259500D03*
X211600Y456500D03*
X236400D03*
X520600Y445500D03*
X545400D03*
X741293Y355942D03*
X716493D03*
X741293Y330892D03*
X716493D03*
G54D48*
X62500Y292200D03*
Y287200D03*
Y282200D03*
Y277200D03*
X42500D03*
Y282200D03*
Y287200D03*
Y292200D03*
X62404Y319922D03*
Y314922D03*
Y309922D03*
Y304922D03*
X42404D03*
Y309922D03*
Y314922D03*
Y319922D03*
G54D93*
X564065Y229550D03*
X561865D03*
X564065Y227250D03*
X561865D03*
X562430Y235988D03*
X560230D03*
X562430Y238288D03*
X560230D03*
X561540Y245859D03*
X559340D03*
X561540Y243559D03*
X559340D03*
X563219Y253446D03*
X561019D03*
X563219Y251146D03*
X561019D03*
G54D57*
X88600Y199400D03*
Y209400D03*
Y204400D03*
X176100Y104500D03*
X194457Y153196D03*
X261800Y431000D03*
X280800Y141000D03*
X280300Y163000D03*
X280800Y204500D03*
X280300Y183000D03*
X280800Y224500D03*
X280300Y246000D03*
X324259Y301695D03*
X576100Y489700D03*
X694900Y306300D03*
X649260Y390820D03*
X690300Y377500D03*
G54D39*
X59800Y183100D03*
X82600Y222700D03*
X176500Y169800D03*
X178500Y193200D03*
X297000Y159200D03*
X296500Y200300D03*
Y242350D03*
X569070Y460430D03*
X581000Y392700D03*
X695700Y390250D03*
X647623Y378489D03*
X642907D03*
X715800Y381800D03*
X736400Y456600D03*
G54D85*
X295275Y531496D03*
X531495D03*
G54D58*
X83000Y199400D03*
Y209400D03*
Y204400D03*
X170500Y104500D03*
X188857Y153196D03*
X256200Y431000D03*
X275200Y141000D03*
X274700Y163000D03*
X275200Y204500D03*
X274700Y183000D03*
X275200Y224500D03*
X274700Y246000D03*
X318659Y301695D03*
X570500Y489700D03*
X689300Y306300D03*
X643660Y390820D03*
X684700Y377500D03*
G54D67*
X193264Y136148D03*
X605570Y472980D03*
G54D49*
X75400Y318200D03*
X50300Y387500D03*
X77700Y291700D03*
X99450Y452650D03*
X225800Y95000D03*
X245300D03*
X242600Y279700D03*
X235400Y316900D03*
X253775Y316967D03*
X218000Y317000D03*
X273165Y317151D03*
X294900Y328300D03*
X360100Y334000D03*
X629800Y166500D03*
X632800Y299091D03*
Y288745D03*
Y337500D03*
Y327654D03*
X626370Y369320D03*
X627070Y389940D03*
X590150Y482900D03*
X599300Y434500D03*
X693535Y441196D03*
X717700Y489400D03*
G54D94*
X535313Y298880D03*
X537513D03*
X535313Y296680D03*
X537513D03*
X535048Y306421D03*
X537248D03*
X535048Y304221D03*
X537248D03*
X535228Y311698D03*
X537428D03*
X535300Y319400D03*
X537500D03*
X535228Y313898D03*
X537428D03*
X535300Y317200D03*
X537500D03*
G54D76*
X254124Y180500D03*
X221876D03*
G54D77*
X229700Y384200D03*
X254920Y376270D03*
G54D59*
X125850Y183400D03*
X141350D03*
X644681Y314583D03*
X660181D03*
G54D95*
X560513Y441531D03*
X582399D03*
G54D68*
X171694Y134453D03*
Y132484D03*
Y130516D03*
Y128547D03*
X183906D03*
Y130516D03*
Y132484D03*
Y134453D03*
G54D86*
X388189Y48426D03*
X374016D03*
X359843D03*
X345670D03*
X388189Y34252D03*
X374016D03*
X359843D03*
X345670D03*
X388189Y20079D03*
X374016D03*
X359843D03*
X345670D03*
X388189Y44095D03*
X374016D03*
X359843D03*
X345670D03*
X388189Y38583D03*
X374016D03*
X359843D03*
X345670D03*
X388189Y29922D03*
X374016D03*
X359843D03*
X345670D03*
X388189Y24410D03*
X374016D03*
X359843D03*
X345670D03*
X388189Y15748D03*
X374016D03*
X359843D03*
X345670D03*
X388189Y10237D03*
X374016D03*
X359843D03*
X345670D03*
X388189Y5906D03*
X374016D03*
X359843D03*
X345670D03*
X381103Y38977D03*
X366929D03*
X352756D03*
X338583D03*
X381103Y24804D03*
X366929D03*
X352756D03*
X338583D03*
X381103Y53150D03*
X366929D03*
X352756D03*
X338583D03*
X381103Y48819D03*
X366929D03*
X352756D03*
X338583D03*
X381103Y43307D03*
X366929D03*
X352756D03*
X338583D03*
X381103Y34646D03*
X366929D03*
X352756D03*
X338583D03*
X381103Y29134D03*
X366929D03*
X352756D03*
X338583D03*
X381103Y20473D03*
X366929D03*
X352756D03*
X338583D03*
X381103Y14961D03*
X366929D03*
X352756D03*
X338583D03*
X444882Y48426D03*
X430709D03*
X416536D03*
X402363D03*
X444882Y34252D03*
X430709D03*
X416536D03*
X402363D03*
X444882Y20079D03*
X430709D03*
X416536D03*
X402363D03*
X444882Y44095D03*
X430709D03*
X416536D03*
X402363D03*
X444882Y38583D03*
X430709D03*
X416536D03*
X402363D03*
X444882Y29922D03*
X430709D03*
X416536D03*
X402363D03*
X444882Y24410D03*
X430709D03*
X416536D03*
X402363D03*
X444882Y15748D03*
X430709D03*
X416536D03*
X402363D03*
X444882Y10237D03*
X430709D03*
X416536D03*
X402363D03*
X444882Y5906D03*
X430709D03*
X416536D03*
X402363D03*
X437796Y38977D03*
X423622D03*
X409449D03*
X395276D03*
X437796Y24804D03*
X423622D03*
X409449D03*
X395276D03*
X437796Y53150D03*
X423622D03*
X409449D03*
X395276D03*
X437796Y48819D03*
X423622D03*
X409449D03*
X395276D03*
X437796Y43307D03*
X423622D03*
X409449D03*
X395276D03*
X437796Y34646D03*
X423622D03*
X409449D03*
X395276D03*
X437796Y29134D03*
X423622D03*
X409449D03*
X395276D03*
X437796Y20473D03*
X423622D03*
X409449D03*
X395276D03*
X437796Y14961D03*
X423622D03*
X409449D03*
X395276D03*
X501575Y48426D03*
X487402D03*
X473229D03*
X459055D03*
X501575Y34252D03*
X487402D03*
X473229D03*
X459055D03*
X501575Y20079D03*
X487402D03*
X473229D03*
X459055D03*
X501575Y44095D03*
X487402D03*
X473229D03*
X459055D03*
X501575Y38583D03*
X487402D03*
X473229D03*
X459055D03*
X501575Y29922D03*
X487402D03*
X473229D03*
X459055D03*
X501575Y24410D03*
X487402D03*
X473229D03*
X459055D03*
X501575Y15748D03*
X487402D03*
X473229D03*
X459055D03*
X501575Y10237D03*
X487402D03*
X473229D03*
X459055D03*
X501575Y5906D03*
X487402D03*
X473229D03*
X459055D03*
X508662Y38977D03*
X494489D03*
X480315D03*
X466142D03*
X451969D03*
X508662Y24804D03*
X494489D03*
X480315D03*
X466142D03*
X451969D03*
X508662Y53150D03*
X494489D03*
X480315D03*
X466142D03*
X451969D03*
X508662Y48819D03*
X494489D03*
X480315D03*
X466142D03*
X451969D03*
X508662Y43307D03*
X494489D03*
X480315D03*
X466142D03*
X451969D03*
X508662Y34646D03*
X494489D03*
X480315D03*
X466142D03*
X451969D03*
X508662Y29134D03*
X494489D03*
X480315D03*
X466142D03*
X451969D03*
X508662Y20473D03*
X494489D03*
X480315D03*
X466142D03*
X451969D03*
X508662Y14961D03*
X494489D03*
X480315D03*
X466142D03*
X451969D03*
X572441Y48426D03*
X558268D03*
X544095D03*
X529922D03*
X515748D03*
X572441Y34252D03*
X558268D03*
X544095D03*
X529922D03*
X515748D03*
X572441Y20079D03*
X558268D03*
X544095D03*
X529922D03*
X515748D03*
X572441Y44095D03*
X558268D03*
X544095D03*
X529922D03*
X515748D03*
X572441Y38583D03*
X558268D03*
X544095D03*
X529922D03*
X515748D03*
X572441Y29922D03*
X558268D03*
X544095D03*
X529922D03*
X515748D03*
X572441Y24410D03*
X558268D03*
X544095D03*
X529922D03*
X515748D03*
X572441Y15748D03*
X558268D03*
X544095D03*
X529922D03*
X515748D03*
X572441Y10237D03*
X558268D03*
X544095D03*
X529922D03*
X515748D03*
X572441Y5906D03*
X558268D03*
X544095D03*
X529922D03*
X515748D03*
X565355Y38977D03*
X551181D03*
X537008D03*
X522835D03*
X565355Y24804D03*
X551181D03*
X537008D03*
X522835D03*
X565355Y53150D03*
X551181D03*
X537008D03*
X522835D03*
X565355Y48819D03*
X551181D03*
X537008D03*
X522835D03*
X565355Y43307D03*
X551181D03*
X537008D03*
X522835D03*
X565355Y34646D03*
X551181D03*
X537008D03*
X522835D03*
X565355Y29134D03*
X551181D03*
X537008D03*
X522835D03*
X565355Y20473D03*
X551181D03*
X537008D03*
X522835D03*
X565355Y14961D03*
X551181D03*
X537008D03*
X522835D03*
X586614Y48426D03*
Y34252D03*
Y20079D03*
Y44095D03*
Y38583D03*
Y29922D03*
Y24410D03*
Y15748D03*
Y10237D03*
Y5906D03*
X579528Y38977D03*
Y24804D03*
Y53150D03*
Y48819D03*
Y43307D03*
Y34646D03*
Y29134D03*
Y20473D03*
Y14961D03*
X758267Y48426D03*
X744094D03*
X729921D03*
X715748D03*
X758267Y44095D03*
X744094D03*
X729921D03*
X715748D03*
X758267Y38583D03*
X744094D03*
X729921D03*
X715748D03*
X758267Y34252D03*
X744094D03*
X729921D03*
X715748D03*
X758267Y29922D03*
X744094D03*
X729921D03*
X715748D03*
X758267Y24410D03*
X744094D03*
X729921D03*
X715748D03*
X758267Y20079D03*
X744094D03*
X729921D03*
X715748D03*
X758267Y15748D03*
X744094D03*
X729921D03*
X715748D03*
X758267Y10237D03*
X744094D03*
X729921D03*
X715748D03*
X758267Y5906D03*
X744094D03*
X729921D03*
X715748D03*
X751181Y53150D03*
X737007D03*
X722834D03*
X708661D03*
X751181Y48819D03*
X737007D03*
X722834D03*
X708661D03*
X751181Y43307D03*
X737007D03*
X722834D03*
X708661D03*
X751181Y38977D03*
X737007D03*
X722834D03*
X708661D03*
X751181Y34646D03*
X737007D03*
X722834D03*
X708661D03*
X751181Y29134D03*
X737007D03*
X722834D03*
X708661D03*
X751181Y24804D03*
X737007D03*
X722834D03*
X708661D03*
X751181Y20473D03*
X737007D03*
X722834D03*
X708661D03*
X751181Y14961D03*
X737007D03*
X722834D03*
X708661D03*
G54D87*
X341757Y215563D03*
X335701D03*
X341757Y219461D03*
X335701D03*
G54D69*
X180753Y137606D03*
X178784D03*
X176816D03*
X174847D03*
Y125394D03*
X176816D03*
X178784D03*
X180753D03*
G54D96*
X562460Y462070D03*
Y471070D03*
G54D78*
X235300Y384200D03*
X260520Y376270D03*
G54D88*
X340250Y292980D03*
X332750Y296855D03*
Y289105D03*
G54D79*
X251870Y395670D03*
G54D97*
X634216Y47468D03*
Y25268D03*
X651536Y47468D03*
X649961D03*
X648386D03*
X646811D03*
X645236D03*
X643661D03*
X642091D03*
X640516D03*
X638941D03*
X637366D03*
X635791D03*
Y25268D03*
X637366D03*
X638941D03*
X640516D03*
X642091D03*
X643661D03*
X645236D03*
X646811D03*
X648386D03*
X649961D03*
X651536D03*
G54D98*
X623566Y173443D03*
X627464D03*
X623566Y179499D03*
X627464D03*
G54D89*
G01X427165Y234252D02*
X425197Y236220D01*
G01X450787Y226378D02*
X448818Y228347D01*
G01X407480Y214567D02*
X405512Y212599D01*
G01X403543Y210630D02*
X401575Y208662D01*
G01X411417Y210630D02*
X409449Y208662D01*
G01X419291Y210630D02*
X417323Y208662D01*
G01X427165Y210630D02*
X425197Y208662D01*
G01X435039Y210630D02*
X433071Y208662D01*
G01X442913Y210630D02*
X440945Y208662D01*
G01X450787Y210630D02*
X448819Y208662D01*
G01X415354Y214567D02*
X413386Y212599D01*
G01X423228Y214567D02*
X421260Y212599D01*
G01X431102Y214567D02*
X429134Y212599D01*
G01X438976Y214567D02*
X437008Y212599D01*
G01X446850Y214567D02*
X444882Y212599D01*
G01X446850Y230315D02*
X448818Y228347D01*
G01X438976Y230315D02*
X440944Y228347D01*
G01X442913Y226378D02*
X440944Y228347D01*
G01X435039Y226378D02*
X433070Y228347D01*
G01X431102Y230315D02*
X433070Y228347D01*
G01X450787Y234252D02*
X448818Y236221D01*
G01X446850Y238189D02*
X448818Y236221D01*
G01X442913Y234252D02*
X440944Y236221D01*
G01X438976Y238189D02*
X440944Y236221D01*
G01X435039Y234252D02*
X433070Y236221D01*
G01X431102Y238189D02*
X433070Y236221D01*
G01X423228Y230315D02*
X425196Y228347D01*
G01X421258Y232283D02*
X419290Y230315D01*
X419291D01*
G01X431102Y234252D02*
X427165Y238189D01*
G01X438976Y234252D02*
X435039Y238189D01*
G01X446850Y234252D02*
X442913Y238189D01*
G01X431102Y234252D02*
X433070Y232284D01*
G01X438976Y234252D02*
X440944Y232284D01*
G01X446850Y234252D02*
X448818Y232284D01*
G01X391732Y222441D02*
X389764Y220473D01*
G01X391732Y230315D02*
X389764Y228347D01*
G01X411417Y238189D02*
X409449Y236221D01*
G01X395669Y230315D02*
X393701Y228347D01*
G01X395669Y218504D02*
X393701Y216536D01*
G01X395669Y214567D02*
X393701Y212599D01*
G01X399606Y214567D02*
X397638Y212599D01*
G01X403543Y214567D02*
X401575Y212599D01*
G01X395669Y222441D02*
X393701Y220473D01*
G01X407480Y202756D02*
X405512Y200788D01*
G01X415354Y202756D02*
X413386Y200788D01*
G01X423228Y202756D02*
X421260Y200788D01*
G01X431102Y202756D02*
X429134Y200788D01*
G01X438976Y202756D02*
X437008Y200788D01*
G01X446850Y202756D02*
X444882Y200788D01*
G01X411417Y214567D02*
X409449Y212599D01*
G01X411417Y226378D02*
X409449Y224410D01*
G01X419291Y214567D02*
X417323Y212599D01*
G01X427165Y214567D02*
X425197Y212599D01*
G01X435039Y214567D02*
X433071Y212599D01*
G01X442913Y214567D02*
X440945Y212599D01*
G01X450787Y214567D02*
X448819Y212599D01*
G01X399606Y234252D02*
X397638Y232284D01*
G01X427165Y226378D02*
X425197Y224410D01*
G01X419291Y226378D02*
X417323Y224410D01*
G01X415354Y226378D02*
X413386Y224410D01*
G01X411417Y230315D02*
X415354Y226378D01*
G01X407480D02*
X407481D01*
X409449Y224410D01*
G01X403543Y226378D02*
X403774Y226147D01*
X407249D01*
X407480Y226378D01*
G01X446850D02*
X446851D01*
X448819Y224410D01*
G01X438976Y226378D02*
X438977D01*
X440945Y224410D01*
G01X442913Y230315D02*
X446850Y226378D01*
G01X435039Y230315D02*
X438976Y226378D01*
G01X431102D02*
X431103D01*
X433071Y224410D01*
G01X427165Y230315D02*
X431102Y226378D01*
G01X423228D02*
X423229D01*
X425197Y224410D01*
G01X433070Y232284D02*
X435039Y230315D01*
G01X440944Y232284D02*
X442913Y230315D01*
G01X448818Y232284D02*
X450787Y230315D01*
G01X442913Y238189D02*
Y238190D01*
X440945Y240158D01*
G01X435039Y238189D02*
Y238190D01*
X433071Y240158D01*
G01X415354Y230315D02*
X419291Y226378D01*
G01Y234252D02*
Y234250D01*
X421258Y232283D01*
G01X423228Y238189D02*
X419291Y234252D01*
G01X423228D02*
X423227D01*
X421258Y232283D01*
G01X411417Y234252D02*
X409449Y232284D01*
G01X399606Y238189D02*
X397638Y236221D01*
G01X399606Y230315D02*
X397638Y228347D01*
G01X399606Y226378D02*
X397638Y224410D01*
G01X423228Y285434D02*
X425196Y283466D01*
G01X399606Y293308D02*
X397638Y295276D01*
G01X407480Y293308D02*
X405512Y295276D01*
G01X399606Y269686D02*
X397638Y271654D01*
G01X411417Y265749D02*
X409449Y267717D01*
G01X399606Y285434D02*
X397638Y287402D01*
G01X407480Y285434D02*
X405512Y287402D01*
G01X399606Y277560D02*
X397638Y279528D01*
G01X411417Y273623D02*
X409449Y275591D01*
G01X399606Y261811D02*
X397638Y259843D01*
G01X407480Y261811D02*
X405512Y259843D01*
G01X391732Y253937D02*
X389764Y251969D01*
G01X395669Y253937D02*
X393701Y251969D01*
G01X399606Y253937D02*
X397638Y251969D01*
G01X411417Y246063D02*
X409449Y244095D01*
G01X411417Y257874D02*
X409449Y255906D01*
G01X399606Y242126D02*
X397638Y240158D01*
G01X423228Y289371D02*
X421260Y291339D01*
G01X427165Y261811D02*
X425197Y259843D01*
G01X419291Y265749D02*
X417323Y267717D01*
G01X431102Y269686D02*
X429134Y271654D01*
G01X419291Y273623D02*
X417323Y275591D01*
G01X431102Y250000D02*
X429134Y248032D01*
G01X427165Y257874D02*
X425197Y255906D01*
G01X419291Y257874D02*
X417323Y255906D01*
G01X415354Y261811D02*
X413386Y259843D01*
G01X431102Y277560D02*
X429134Y279528D01*
G01X423228Y277560D02*
X421260Y279528D01*
G01X435039Y242126D02*
X433071Y240158D01*
G01X435039Y250000D02*
X433071Y248032D01*
G01X450787Y242126D02*
X448819Y240158D01*
G01X442913Y242126D02*
X440945Y240158D01*
G01X450787Y250000D02*
X448819Y248032D01*
G01X442913Y250000D02*
X440945Y248032D01*
G01X435039Y273623D02*
X433071Y275591D01*
G01X419291Y297245D02*
X417323Y299213D01*
G01X431102Y253937D02*
X433070Y255905D01*
G01X405512Y255906D02*
X407480Y253938D01*
Y253937D01*
G01X438976Y277560D02*
X438911D01*
X437057Y279414D01*
G01X433070Y279528D02*
X431102Y281496D01*
Y281497D01*
G01X440945Y248032D02*
X438977Y250000D01*
X438976D01*
G01X448819Y248032D02*
X446851Y250000D01*
X446850D01*
G01X440945Y240158D02*
X438977Y242126D01*
X438976D01*
G01X448819Y240158D02*
X446851Y242126D01*
X446850D01*
G01X433071Y240158D02*
X431103Y242126D01*
X431102D01*
G01X421260Y279528D02*
X419291Y281497D01*
G01X429134Y279528D02*
X427165Y281497D01*
G01X429134Y248032D02*
X427165Y246063D01*
G01X425197Y259843D02*
X423229Y261811D01*
X423228D01*
G01X409449Y255906D02*
X411417Y253938D01*
Y253937D01*
G01X438976D02*
X435039Y250000D01*
G01X446850Y253937D02*
X442913Y250000D01*
G01X403543Y253937D02*
X405512Y255906D01*
G01X399606Y250000D02*
Y250001D01*
X397638Y251969D01*
G01X427165Y242126D02*
X431102D01*
G01X423228Y293308D02*
Y293307D01*
X421260Y291339D01*
G01X407480Y277560D02*
X409449Y275591D01*
G01X415354Y269686D02*
X417323Y267717D01*
G01X415354Y277560D02*
X417323Y275591D01*
G01X407480Y269686D02*
X409449Y267717D01*
G01X427165Y273623D02*
X429134Y271654D01*
G01X446850Y301182D02*
X448818Y299214D01*
G01X450787Y238189D02*
Y238190D01*
X448819Y240158D01*
G01X423228Y269686D02*
X419291Y273623D01*
G01X427165Y253937D02*
X429134Y255906D01*
G01X431102Y257874D02*
X429134Y255906D01*
G01X435039Y281497D02*
X433071Y283465D01*
G01X427165Y285434D02*
X425197Y287402D01*
G01X444882D02*
X446850Y285434D01*
G01X450787Y281497D02*
X448819Y283465D01*
G01X442913Y281497D02*
X440945Y283465D01*
G01X448819D02*
X446850Y285434D01*
G01X440945Y283465D02*
X438976Y285434D01*
G01X446850Y297245D02*
X444882Y299213D01*
G01X423228Y242126D02*
X425196Y240158D01*
G01X411417Y242126D02*
X409449Y240158D01*
G01X411417Y250000D02*
X409449Y248032D01*
G01X399606Y246063D02*
X397638Y244095D01*
G01X423228Y257874D02*
X421260Y255906D01*
G01X419291Y261811D02*
X417323Y259843D01*
G01X415354Y257874D02*
X413386Y255906D01*
G01X427165Y250000D02*
X429134Y251969D01*
G01X435039Y246063D02*
X433071Y244095D01*
G01X442913Y246063D02*
X440945Y244095D01*
G01X450787Y246063D02*
X448819Y244095D01*
G01X433071D02*
X431103Y246063D01*
X431102D01*
G01X440945Y244095D02*
X438977Y246063D01*
X438976D01*
G01X448819Y244095D02*
X446851Y246063D01*
X446850D01*
G01X411417Y324804D02*
X409449Y326772D01*
G01X411417Y316930D02*
X409449Y318898D01*
G01X411417Y312993D02*
X409449Y314961D01*
G01X399606Y309056D02*
X397638Y311024D01*
G01X411417Y309056D02*
X409449Y311024D01*
G01X419291Y324804D02*
X417323Y326772D01*
G01X419291Y316930D02*
X417323Y318898D01*
G01X427165Y309056D02*
X425197Y311024D01*
G01X435039Y309056D02*
X433071Y311024D01*
G01X399606Y301182D02*
X397638Y303150D01*
G01X407480Y301182D02*
X405512Y303150D01*
G01X415354Y305119D02*
X413386Y307087D01*
G01X442913Y316930D02*
X440945Y318898D01*
G01X450787Y316930D02*
X448819Y318898D01*
G01X419291Y305119D02*
X417323Y307087D01*
G01X419291Y301182D02*
X417323Y303150D01*
G01X415354Y309056D02*
Y309055D01*
X413386Y307087D01*
G01X411417Y320867D02*
Y320866D01*
X409449Y318898D01*
G01X415354Y324804D02*
X413386Y326772D01*
G01X427165Y305119D02*
X425197Y307087D01*
G01X419291Y312993D02*
X417323Y314961D01*
G01X435039Y305119D02*
X433071Y307087D01*
G01X450787Y312993D02*
X448819Y314961D01*
G01X442913Y312993D02*
X440945Y314961D01*
G01X458662Y210630D02*
X460630Y208662D01*
G01X466536Y210630D02*
X468504Y208662D01*
G01X482284Y210630D02*
X484252Y208662D01*
G01X474410Y210630D02*
X476378Y208662D01*
G01X494095Y210630D02*
X496063Y208662D01*
G01X454725Y214567D02*
X456693Y212599D01*
G01X462599Y214567D02*
X464567Y212599D01*
G01X501969Y218504D02*
X503937Y216536D01*
G01X470473Y214567D02*
X472441Y212599D01*
G01X478347Y214567D02*
X480315Y212599D01*
G01X486221Y214567D02*
X488189Y212599D01*
G01X505906Y214567D02*
X507874Y212599D01*
G01X505906Y238189D02*
X507874Y236221D01*
G01X501969Y234252D02*
X503937Y232284D01*
G01X505906Y230315D02*
X507874Y228347D01*
G01X501969Y226378D02*
X503937Y224410D01*
G01X505906Y222441D02*
X507874Y220473D01*
G01X470473Y230315D02*
X472441Y228347D01*
G01X462599Y230315D02*
X464567Y228347D01*
G01X454725Y230315D02*
X456693Y228347D01*
G01X478347Y230315D02*
X480315Y228347D01*
G01X482284Y238189D02*
X484252Y236221D01*
G01X486221Y234252D02*
X488189Y232284D01*
G01X458662Y226378D02*
X456693Y228347D01*
G01X466536Y226378D02*
X464567Y228347D01*
G01X474410Y226378D02*
X472441Y228347D01*
G01X482284Y226378D02*
X480315Y228347D01*
G01X474410Y234252D02*
X472441Y236221D01*
G01X470473Y238189D02*
X472441Y236221D01*
G01X466536Y234252D02*
X464567Y236221D01*
G01X462599Y238189D02*
X464567Y236221D01*
G01X458662Y234252D02*
X456693Y236221D01*
G01X454725Y238189D02*
X456693Y236221D01*
G01X454725Y234252D02*
X454724D01*
X450787Y238189D01*
G01X462599Y234252D02*
X458662Y238189D01*
G01X478347Y234252D02*
X480315Y232284D01*
G01X470473Y234252D02*
X472441Y232284D01*
G01X462599Y234252D02*
X464567Y232284D01*
G01X454725Y234252D02*
X456693Y232284D01*
G01X454725Y202756D02*
X456693Y200788D01*
G01X462599Y202756D02*
X464567Y200788D01*
G01X490158Y210630D02*
X492126Y208662D01*
G01X490158Y206693D02*
X492126Y204725D01*
G01X498032Y206693D02*
X500000Y204725D01*
G01X470473Y202756D02*
X472441Y200788D01*
G01X478347Y202756D02*
X480315Y200788D01*
G01X486221Y202756D02*
X488189Y200788D01*
G01X490158Y202756D02*
X492126Y200788D01*
G01X458662Y214567D02*
X460630Y212599D01*
G01X466536Y214567D02*
X468504Y212599D01*
G01X490158Y218504D02*
X492126Y216536D01*
G01X474410Y214567D02*
X476378Y212599D01*
G01X482284Y214567D02*
X484252Y212599D01*
G01X490158Y214567D02*
X492126Y212599D01*
G01X501969Y214567D02*
X503937Y212599D01*
G01X501969Y206693D02*
X503937Y204725D01*
G01X501969Y238189D02*
X503937Y236221D01*
G01X501969Y230315D02*
X503937Y228347D01*
G01X490158Y222441D02*
X492126Y220473D01*
G01X501969Y222441D02*
X503937Y220473D01*
G01X470473Y226378D02*
X472441Y224410D01*
G01X462599Y226378D02*
X464567Y224410D01*
G01X454725Y226378D02*
X456693Y224410D01*
G01X478347Y226378D02*
X480315Y224410D01*
G01X490158Y226378D02*
X492126Y224410D01*
G01X486221Y226378D02*
X488189Y224410D01*
G01X490158Y234252D02*
X492126Y232284D01*
G01X490158Y238189D02*
X492126Y236221D01*
G01X488189Y240158D02*
X486221Y238190D01*
Y238189D01*
G01X492126Y200788D02*
X494094Y202756D01*
X494095D01*
G01X492126Y204725D02*
X494094Y206693D01*
X494095D01*
G01X486221Y230315D02*
X490158Y226378D01*
G01X482284Y230315D02*
X486221Y226378D01*
G01X474410Y230315D02*
X478347Y226378D01*
G01X466536Y230315D02*
X470473Y226378D01*
G01X458662Y230315D02*
X462599Y226378D01*
G01X450787Y230315D02*
X450788D01*
X454725Y226378D01*
G01X480315Y232284D02*
X482284Y230315D01*
G01X472441Y232284D02*
X474410Y230315D01*
G01X464567Y232284D02*
X466536Y230315D01*
G01X456693Y232284D02*
X458662Y230315D01*
G01X474410Y238189D02*
X472441Y240158D01*
G01X466536Y238189D02*
X470473Y234252D01*
G01X474410Y238189D02*
X478347Y234252D01*
G01X466536Y238189D02*
X464567Y240158D01*
G01X458662Y238189D02*
X456693Y240158D01*
G01X482284Y234252D02*
X482283D01*
X480315Y232284D01*
G01X478347Y238189D02*
Y238190D01*
X480315Y240158D01*
G01X490158Y230315D02*
Y230316D01*
X492126Y232284D01*
G01X501969Y257874D02*
X503937Y255906D01*
G01X505906Y253937D02*
X507874Y251969D01*
G01X501969Y250000D02*
X503937Y248032D01*
G01X505906Y246063D02*
X507874Y244095D01*
G01X501969Y242126D02*
X503937Y240158D01*
G01X505906Y269686D02*
X507874Y271654D01*
G01X501969Y265749D02*
X503937Y267717D01*
G01X505906Y261811D02*
X507874Y259843D01*
G01X505906Y285434D02*
X507874Y287402D01*
G01X501969Y281497D02*
X503937Y283465D01*
G01X505906Y277560D02*
X507874Y279528D01*
G01X501969Y273623D02*
X503937Y275591D01*
G01X501969Y297245D02*
X503937Y299213D01*
G01X505906Y293308D02*
X507874Y295276D01*
G01X501969Y289371D02*
X503937Y291339D01*
G01X490158Y285434D02*
X492126Y287402D01*
G01X482284Y269686D02*
X484252Y271654D01*
G01X482284Y277560D02*
X484252Y279528D01*
G01X486221Y265749D02*
X488189Y267717D01*
G01X486221Y273623D02*
X488189Y275591D01*
G01X490158Y269686D02*
X492126Y271654D01*
G01X490158Y277560D02*
X492126Y279528D01*
G01X486221Y281497D02*
X488189Y283465D01*
G01X482284Y261811D02*
X484252Y259843D01*
G01X482284Y253937D02*
X484252Y251969D01*
G01X482284Y246063D02*
X484252Y244095D01*
G01X490158Y261811D02*
X492126Y259843D01*
G01X490158Y253937D02*
X492126Y251969D01*
G01X490158Y246063D02*
X492126Y244095D01*
G01X462599Y301182D02*
X464567Y299214D01*
G01X501969Y253937D02*
X503937Y251969D01*
G01X501969Y246063D02*
X503937Y244095D01*
G01X501969Y269686D02*
X503937Y271654D01*
G01X501969Y261811D02*
X503937Y259843D01*
G01X501969Y285434D02*
X503937Y287402D01*
G01X501969Y277560D02*
X503937Y279528D01*
G01X501969Y293308D02*
X503937Y295276D01*
G01X486221Y285434D02*
X488189Y287402D01*
G01X490158Y289371D02*
X492126Y291339D01*
G01X486221Y289371D02*
X488189Y291339D01*
G01X470473Y242126D02*
X472441Y240158D01*
G01X462599Y242126D02*
X464567Y240158D01*
G01X454725Y242126D02*
X456693Y240158D01*
G01X478347Y265749D02*
X480315Y267717D01*
G01X478347Y269686D02*
X480315Y271654D01*
G01X478347Y273623D02*
X480315Y275591D01*
G01X478347Y277560D02*
X480315Y279528D01*
G01X478347Y281497D02*
X480315Y283465D01*
G01X490158Y265749D02*
X492126Y267717D01*
G01X486221Y269686D02*
X488189Y271654D01*
G01X490158Y273623D02*
X492126Y275591D01*
G01X486221Y277560D02*
X488189Y279528D01*
G01X490158Y281497D02*
X492126Y283465D01*
G01X478347Y261811D02*
X480315Y259843D01*
G01X478347Y242126D02*
X480315Y240158D01*
G01X478347Y246063D02*
X480315Y244095D01*
G01X478347Y250000D02*
X480315Y248032D01*
G01X478347Y253937D02*
X480315Y251969D01*
G01X478347Y257874D02*
X480315Y255906D01*
G01X486221Y261811D02*
X488189Y259843D01*
G01X490158Y242126D02*
X492126Y240158D01*
G01X486221Y242126D02*
X488189Y240158D01*
G01X490158Y250000D02*
X492126Y248032D01*
G01X486221Y250000D02*
X488189Y248032D01*
G01X486221Y257874D02*
X488189Y255906D01*
G01X470473Y273623D02*
X472441Y275591D01*
G01X470473Y265749D02*
X472441Y267717D01*
G01X470473Y281497D02*
X472441Y283465D01*
G01X470473Y261811D02*
X472441Y259843D01*
G01X470473Y253937D02*
X472441Y251969D01*
G01X454725Y250000D02*
X456693Y248032D01*
G01X462599Y250000D02*
X464567Y248032D01*
G01D02*
X466535Y250000D01*
X466536D01*
G01X456693Y248032D02*
X458661Y250000D01*
X458662D01*
G01X472441Y251969D02*
X470473Y250001D01*
Y250000D01*
G01X472441Y259843D02*
X470473Y257875D01*
Y257874D01*
G01X472441Y283465D02*
X474409Y281497D01*
X474410D01*
G01X472441Y267717D02*
X470473Y269685D01*
Y269686D01*
G01X472441Y275591D02*
X470473Y277559D01*
Y277560D01*
G01X488189Y255906D02*
X486221Y253938D01*
Y253937D01*
G01X488189Y248032D02*
X486221Y246064D01*
Y246063D01*
G01X488189Y259843D02*
X490158Y257874D01*
G01X480315Y255906D02*
X482283Y257874D01*
X482284D01*
G01X480315Y248032D02*
X482283Y250000D01*
X482284D01*
G01X480315Y240158D02*
X482283Y242126D01*
X482284D01*
G01X480315Y283465D02*
X482283Y281497D01*
X482284D01*
G01X480315Y275591D02*
X482283Y273623D01*
X482284D01*
G01X480315Y267717D02*
X482283Y265749D01*
X482284D01*
G01X456693Y240158D02*
X458661Y242126D01*
X458662D01*
G01X464567Y240158D02*
X466535Y242126D01*
X466536D01*
G01X472441Y240158D02*
X474409Y242126D01*
X474410D01*
G01X492126Y291339D02*
X490158Y293307D01*
Y293308D01*
G01X454725Y253937D02*
X454724D01*
X450787Y250000D01*
G01X462599Y253937D02*
X458662Y250000D01*
G01X466536Y273623D02*
X470473Y269686D01*
G01X478347Y285434D02*
X476379Y287402D01*
G01X470473Y297245D02*
X472441Y299213D01*
G01X478347Y297245D02*
X480315Y299213D01*
G01X486221Y297245D02*
X488189Y299213D01*
G01X454725Y285434D02*
X456693Y287402D01*
G01X466536Y281497D02*
X468504Y283465D01*
G01X458662Y281497D02*
X460630Y283465D01*
G01X468504D02*
X470473Y285434D01*
G01X460630Y283465D02*
X462599Y285434D01*
G01X470473D02*
X468505Y287402D01*
G01X462599Y297245D02*
X460631Y295277D01*
G01X454725Y297245D02*
X456693Y299213D01*
G01X474410Y265749D02*
X476378Y267717D01*
G01X454725Y246063D02*
X456693Y244095D01*
G01X462599Y246063D02*
X464567Y244095D01*
G01X470473Y246063D02*
X472441Y244095D01*
G01X474410Y253937D02*
X476378Y251969D01*
G01X474410Y261811D02*
X476378Y259843D01*
G01X474410Y273623D02*
X476378Y275591D01*
G01X456693Y244095D02*
X458661Y246063D01*
X458662D01*
G01X464567Y244095D02*
X466535Y246063D01*
X466536D01*
G01X472441Y244095D02*
X474409Y246063D01*
X474410D01*
G01X476378Y251969D02*
X474410Y250001D01*
Y250000D01*
G01X476378Y259843D02*
X474410Y257875D01*
Y257874D01*
G01X476378Y275591D02*
X474410Y277559D01*
Y277560D01*
G01X476378Y267717D02*
X474410Y269685D01*
Y269686D01*
G01X505906Y301182D02*
X507874Y303150D01*
G01X470473Y301182D02*
X472441Y303150D01*
G01X458662Y316930D02*
X460630Y318898D01*
G01X466536Y316930D02*
X468504Y318898D01*
G01X454725Y301182D02*
X456693Y303150D01*
G01X474410Y316930D02*
X476378Y318898D01*
G01X482284Y316930D02*
X484252Y318898D01*
G01X490158Y316930D02*
X492126Y318898D01*
G01X498032Y316930D02*
X500000Y318898D01*
G01X494095Y305119D02*
X496063Y307087D01*
G01X478347Y301182D02*
X480315Y303150D01*
G01X505906Y305119D02*
X507874Y307087D01*
G01X509843Y305119D02*
X511811Y307087D01*
G01X501969Y301182D02*
X503937Y303150D01*
G01X490158Y301182D02*
X492126Y303150D01*
G01X498032Y305119D02*
X498031D01*
X496063Y307087D01*
G01X482284Y312993D02*
X484252Y314961D01*
G01X474410Y312993D02*
X476378Y314961D01*
G01X466536Y312993D02*
X468504Y314961D01*
G01X505906Y312993D02*
X507874Y314961D01*
G01X490158Y312993D02*
X492126Y314961D01*
G01X498032Y312993D02*
X500000Y311025D01*
G01X458662Y312993D02*
X460630Y314961D01*
G01X513780Y242126D02*
X515748Y240158D01*
G01X513780Y265749D02*
X515748Y267717D01*
G01X513780Y257874D02*
X515748Y255906D01*
G01X513780Y250000D02*
X515748Y248032D01*
G01X513780Y281497D02*
X515748Y283465D01*
G01X513780Y273623D02*
X515748Y275591D01*
G01X513780Y305119D02*
X515748Y307087D01*
G01X513780Y312993D02*
X516493D01*
X516500Y313000D01*
G01X754450Y97800D02*
Y99303D01*
X752853Y100900D01*
X374432Y316002D03*
X446850Y202756D03*
X442913D03*
X438976D03*
X435039D03*
X431102D03*
X427165D03*
X423228D03*
X419291D03*
X415354D03*
X411417D03*
X407480D03*
X403543D03*
X446850Y206693D03*
X442913D03*
X438976D03*
X435039D03*
X431102D03*
X427165D03*
X423228D03*
X419291D03*
X415354D03*
X411417D03*
X407480D03*
X403543D03*
X446850Y210630D03*
X442913D03*
X438976D03*
X435039D03*
X431102D03*
X427165D03*
X423228D03*
X419291D03*
X415354D03*
X411417D03*
X407480D03*
X403543D03*
X446850Y214567D03*
X442913D03*
X438976D03*
X435039D03*
X431102D03*
X427165D03*
X423228D03*
X419291D03*
X415354D03*
X411417D03*
X407480D03*
X403543D03*
X399606D03*
X395669D03*
X391732D03*
X446850Y218504D03*
X442913D03*
X438976D03*
X435039D03*
X431102D03*
X427165D03*
X423228D03*
X419291D03*
X415354D03*
X411417D03*
X407480D03*
X403543D03*
X399606D03*
X395669D03*
X391732D03*
X446850Y222441D03*
X442913D03*
X438976D03*
X435039D03*
X431102D03*
X427165D03*
X423228D03*
X419291D03*
X415354D03*
X411417D03*
X407480D03*
X403543D03*
X399606D03*
X395669D03*
X391732D03*
X446850Y226378D03*
X442913D03*
X438976D03*
X435039D03*
X431102D03*
X427165D03*
X423228D03*
X419291D03*
X415354D03*
X411417D03*
X407480D03*
X403543D03*
X399606D03*
X395669D03*
X391732D03*
X446850Y230315D03*
X442913D03*
X438976D03*
X435039D03*
X431102D03*
X427165D03*
X423228D03*
X419291D03*
X415354D03*
X411417D03*
X407480D03*
X403543D03*
X399606D03*
X395669D03*
X391732D03*
X446850Y234252D03*
X442913D03*
X438976D03*
X435039D03*
X431102D03*
X427165D03*
X423228D03*
X419291D03*
X415354D03*
X411417D03*
X407480D03*
X403543D03*
X399606D03*
X395669D03*
X391732D03*
X425197Y236220D03*
X425196Y228347D03*
X433070Y236221D03*
X440944D03*
X448818D03*
X433070Y228347D03*
X440944D03*
X448818D03*
X405512Y212599D03*
X393701Y208662D03*
X401575D03*
X409449D03*
X417323D03*
X425197D03*
X433071D03*
X440945D03*
X448819D03*
X413386Y212599D03*
X421260D03*
X429134D03*
X437008D03*
X444882D03*
X421258Y232283D03*
X448818Y232284D03*
X440944D03*
X433070D03*
X433071Y224410D03*
X440945D03*
X448819D03*
X397638Y232284D03*
X389764Y204725D03*
Y220473D03*
Y208662D03*
Y228347D03*
X409449Y236221D03*
X393701Y228347D03*
Y216536D03*
Y212599D03*
X397638D03*
X401575D03*
X393701Y220473D03*
X397638Y200788D03*
X405512D03*
X413386D03*
X421260D03*
X429134D03*
X437008D03*
X444882D03*
X409449Y212599D03*
Y224410D03*
X417323Y212599D03*
X425197D03*
X433071D03*
X440945D03*
X448819D03*
X425197Y224410D03*
X417323D03*
X413386D03*
X409449Y232284D03*
X397638Y236221D03*
Y228347D03*
Y224410D03*
X389000Y236100D03*
X401575Y236221D03*
X405512D03*
X417322D03*
X409449Y220473D03*
Y216536D03*
X413386Y220473D03*
Y216536D03*
X417323Y220473D03*
Y216536D03*
X421260Y220473D03*
Y216536D03*
X425197Y220473D03*
Y216536D03*
X429134Y220473D03*
Y216536D03*
X433071Y220473D03*
Y216536D03*
X437008Y220473D03*
Y216536D03*
X440945Y220473D03*
Y216536D03*
X444882Y220473D03*
Y216536D03*
X448819Y220473D03*
Y216536D03*
X409449Y204725D03*
Y200788D03*
X413386Y208662D03*
Y204725D03*
X417323D03*
Y200788D03*
X421260Y208662D03*
Y204725D03*
X425197D03*
Y200788D03*
X429134Y208662D03*
Y204725D03*
X433071D03*
Y200788D03*
X437008Y208662D03*
Y204725D03*
X440945D03*
Y200788D03*
X444882Y208662D03*
Y204725D03*
X448819D03*
Y200788D03*
X389764Y216536D03*
Y212599D03*
X397638Y220473D03*
Y216536D03*
X401575Y220473D03*
Y216536D03*
X405512Y220473D03*
Y216536D03*
X393701Y204725D03*
Y200788D03*
X397638Y208662D03*
Y204725D03*
X401575D03*
Y200788D03*
X405512Y208662D03*
Y204725D03*
X401575Y232284D03*
X401727Y228641D03*
X405512Y232284D03*
X413386D03*
X405512Y228347D03*
X446850Y238189D03*
X442913D03*
X438976D03*
X435039D03*
X431102D03*
X427165D03*
X423228D03*
X419291D03*
X415354D03*
X411417D03*
X407480D03*
X403543D03*
X399606D03*
X395669D03*
X391732D03*
X446850Y242126D03*
X442913D03*
X438976D03*
X435039D03*
X431102D03*
X427165D03*
X423228D03*
X419291D03*
X415354D03*
X411417D03*
X407480D03*
X403543D03*
X399606D03*
X395669D03*
X391732D03*
X446850Y246063D03*
X442913D03*
X438976D03*
X435039D03*
X431102D03*
X427165D03*
X423228D03*
X419291D03*
X415354D03*
X411417D03*
X407480D03*
X403543D03*
X399606D03*
X395669D03*
X391732D03*
X446850Y250000D03*
X442913D03*
X438976D03*
X435039D03*
X431102D03*
X427165D03*
X423228D03*
X419291D03*
X415354D03*
X411417D03*
X407480D03*
X403543D03*
X399606D03*
X395669D03*
X391732D03*
X446850Y253937D03*
X442913D03*
X438976D03*
X435039D03*
X431102D03*
X427165D03*
X423228D03*
X419291D03*
X415354D03*
X411417D03*
X407480D03*
X403543D03*
X399606D03*
X395669D03*
X391732D03*
X446850Y257874D03*
X442913D03*
X438976D03*
X435039D03*
X431102D03*
X427165D03*
X423228D03*
X419291D03*
X415354D03*
X411417D03*
X407480D03*
X403543D03*
X399606D03*
X395669D03*
X391732D03*
X446850Y261811D03*
X442913D03*
X438976D03*
X435039D03*
X431102D03*
X427165D03*
X423228D03*
X419291D03*
X415354D03*
X411417D03*
X407480D03*
X403543D03*
X399606D03*
X395669D03*
X391732D03*
X446850Y265749D03*
X442913D03*
X438976D03*
X435039D03*
X431102D03*
X427165D03*
X423228D03*
X419291D03*
X415354D03*
X411417D03*
X407480D03*
X403543D03*
X399606D03*
X395669D03*
X391732D03*
X446850Y269686D03*
X442913D03*
X438976D03*
X435039D03*
X431102D03*
X427165D03*
X423228D03*
X419291D03*
X415354D03*
X411417D03*
X407480D03*
X403543D03*
X399606D03*
X395669D03*
X391732D03*
X446850Y273623D03*
X442913D03*
X438976D03*
X435039D03*
X431102D03*
X427165D03*
X423228D03*
X419291D03*
X415354D03*
X411417D03*
X407480D03*
X403543D03*
X399606D03*
X395669D03*
X391732D03*
X446850Y277560D03*
X442913D03*
X438976D03*
X435039D03*
X431102D03*
X427165D03*
X423228D03*
X419291D03*
X415354D03*
X411417D03*
X407480D03*
X403543D03*
X399606D03*
X395669D03*
X391732D03*
X446850Y281497D03*
X442913D03*
X438976D03*
X435039D03*
X431102D03*
X427165D03*
X423228D03*
X419291D03*
X415354D03*
X411417D03*
X407480D03*
X403543D03*
X399606D03*
X395669D03*
X391732D03*
X446850Y285434D03*
X442913D03*
X438976D03*
X435039D03*
X431102D03*
X427165D03*
X423228D03*
X419291D03*
X415354D03*
X411417D03*
X407480D03*
X403543D03*
X399606D03*
X395669D03*
X391732D03*
X446850Y289371D03*
X442913D03*
X438976D03*
X435039D03*
X431102D03*
X427165D03*
X423228D03*
X419291D03*
X415354D03*
X411417D03*
X407480D03*
X403543D03*
X399606D03*
X395669D03*
X391732D03*
X446850Y293308D03*
X442913D03*
X438976D03*
X435039D03*
X431102D03*
X427165D03*
X423228D03*
X419291D03*
X415354D03*
X411417D03*
X407480D03*
X403543D03*
X399606D03*
X395669D03*
X391732D03*
X446850Y297245D03*
X442913D03*
X438976D03*
X435039D03*
X431102D03*
X427165D03*
X423228D03*
X419291D03*
X415354D03*
X411417D03*
X407480D03*
X403543D03*
X399606D03*
X395669D03*
X391732D03*
X409449Y259843D03*
X425197Y291339D03*
X433071Y295276D03*
Y299213D03*
Y291339D03*
X448819Y287403D03*
X448818Y291339D03*
Y295276D03*
X437008Y299213D03*
Y291339D03*
X448818Y299214D03*
X425196Y283466D03*
X433070Y279528D03*
X433071Y275591D03*
X433070Y255905D03*
X437057Y279414D03*
X397638Y240158D03*
Y295276D03*
X405512D03*
X397638Y271654D03*
X409449Y267717D03*
X397638Y287402D03*
X405512D03*
X397638Y279528D03*
X409449Y275591D03*
X397638Y259843D03*
X405512D03*
Y255906D03*
X389764Y251969D03*
X393701D03*
X397638D03*
X409449Y244095D03*
Y255906D03*
X417323Y299213D03*
X421260Y291339D03*
X425197Y259843D03*
X417323Y267717D03*
X429134Y271654D03*
X417323Y275591D03*
X429134Y248032D03*
X425197Y255906D03*
X417323D03*
X413386Y259843D03*
X429134Y279528D03*
X421260D03*
X433071Y240158D03*
Y248032D03*
X448819Y240158D03*
X440945D03*
X444882Y279529D03*
X448819Y248032D03*
X440945D03*
X448818Y259843D03*
Y267718D03*
X440944D03*
X433071Y263781D03*
X440944Y259843D03*
X429134Y295277D03*
Y299214D03*
X437007Y287402D03*
X429134Y291340D03*
X437008Y275591D03*
X444882D03*
X437007Y267718D03*
X448818Y255906D03*
Y263780D03*
Y271655D03*
X440944Y263780D03*
Y271655D03*
X437007Y259843D03*
Y255905D03*
X440944Y255906D03*
X421260Y259843D03*
X429134Y263781D03*
Y255906D03*
X433071Y283465D03*
X425197Y287402D03*
X444882D03*
X440945Y283465D03*
X448819D03*
X444882Y299213D03*
X425196Y240158D03*
X409449D03*
Y248032D03*
X397638Y244095D03*
X421260Y255906D03*
X425197Y299213D03*
X429134Y287403D03*
X417323Y259843D03*
X413386Y255906D03*
X440945Y295276D03*
Y299213D03*
Y291339D03*
Y287402D03*
X437008Y295276D03*
X429134Y251969D03*
X417323D03*
X413386Y248032D03*
X405512D03*
X421260Y251969D03*
X405512Y244095D03*
X401575D03*
X413386D03*
X417323Y248032D03*
X401575Y240158D03*
X405512D03*
X433070Y287402D03*
X413387Y240158D03*
X421260Y248032D03*
X417323Y244095D03*
X413386Y251969D03*
X401575Y248032D03*
X421260Y295277D03*
X448819Y244095D03*
X440945D03*
X433071D03*
X421259Y240158D03*
X421260Y244095D03*
X417323Y240157D03*
X421260Y299214D03*
X425197Y295276D03*
X446850Y301182D03*
X442913D03*
X438976D03*
X435039D03*
X431102D03*
X427165D03*
X423228D03*
X419291D03*
X415354D03*
X411417D03*
X407480D03*
X403543D03*
X399606D03*
X395669D03*
X391732D03*
X446850Y305119D03*
X442913D03*
X438976D03*
X435039D03*
X431102D03*
X427165D03*
X423228D03*
X419291D03*
X415354D03*
X411417D03*
X407480D03*
X403543D03*
X399606D03*
X395669D03*
X391732D03*
X446850Y309056D03*
X442913D03*
X438976D03*
X435039D03*
X431102D03*
X427165D03*
X423228D03*
X419291D03*
X415354D03*
X411417D03*
X407480D03*
X403543D03*
X399606D03*
X395669D03*
X391732D03*
X446850Y312993D03*
X442913D03*
X438976D03*
X435039D03*
X431102D03*
X427165D03*
X423228D03*
X419291D03*
X415354D03*
X411417D03*
X407480D03*
X403543D03*
X399606D03*
X395669D03*
X391732D03*
X446850Y316930D03*
X442913D03*
X438976D03*
X435039D03*
X431102D03*
X427165D03*
X423228D03*
X419291D03*
X415354D03*
X411417D03*
X407480D03*
X403543D03*
X446850Y320867D03*
X442913D03*
X438976D03*
X435039D03*
X431102D03*
X427165D03*
X423228D03*
X419291D03*
X415354D03*
X411417D03*
X407480D03*
X403543D03*
X446850Y324804D03*
X442913D03*
X438976D03*
X435039D03*
X431102D03*
X427165D03*
X423228D03*
X419291D03*
X415354D03*
X411417D03*
X407480D03*
X403543D03*
X413386Y311025D03*
X425197Y318898D03*
Y303150D03*
X429134Y314961D03*
Y311024D03*
X448819Y307088D03*
X448818Y311024D03*
Y303151D03*
X444882Y314961D03*
Y318898D03*
X433071Y314961D03*
X431102Y331263D03*
X397638Y326772D03*
X409449D03*
X397638Y318898D03*
X409449D03*
Y314961D03*
X397638Y311024D03*
X409449D03*
X417323Y326772D03*
Y318898D03*
X425197Y311024D03*
X433071D03*
X397638Y303150D03*
X405512D03*
X413386Y307087D03*
X440945Y318898D03*
X448819D03*
X417323Y307087D03*
Y303150D03*
X429134Y303151D03*
X425197Y314961D03*
X413386Y326772D03*
X425197Y307087D03*
X417323Y314961D03*
X433071Y307087D03*
X448819Y314961D03*
X440945D03*
X417323Y311024D03*
X429134Y318898D03*
X442800Y330300D03*
X446200Y327400D03*
X440945Y303150D03*
Y311024D03*
Y307087D03*
X444881Y322835D03*
X442913Y327204D03*
X440944Y322835D03*
X438976Y327204D03*
X437008Y318898D03*
Y314961D03*
Y311024D03*
Y303150D03*
Y307087D03*
X433071Y318898D03*
X421260Y326772D03*
X421259Y322835D03*
X421260Y318898D03*
Y314961D03*
X417322Y322835D03*
X413386Y314962D03*
X421260Y307088D03*
X433071Y303150D03*
X421260Y303151D03*
X501969Y202756D03*
X498032D03*
X494095D03*
X490158D03*
X486221D03*
X482284D03*
X478347D03*
X474410D03*
X470473D03*
X466536D03*
X462599D03*
X458662D03*
X454725D03*
X450787D03*
X501969Y206693D03*
X498032D03*
X494095D03*
X490158D03*
X486221D03*
X482284D03*
X478347D03*
X474410D03*
X470473D03*
X466536D03*
X462599D03*
X458662D03*
X454725D03*
X450787D03*
X501969Y210630D03*
X498032D03*
X494095D03*
X490158D03*
X486221D03*
X482284D03*
X478347D03*
X474410D03*
X470473D03*
X466536D03*
X462599D03*
X458662D03*
X454725D03*
X450787D03*
X509843Y214567D03*
X505906D03*
X501969D03*
X498032D03*
X494095D03*
X490158D03*
X486221D03*
X482284D03*
X478347D03*
X474410D03*
X470473D03*
X466536D03*
X462599D03*
X458662D03*
X454725D03*
X450787D03*
X509843Y218504D03*
X505906D03*
X501969D03*
X498032D03*
X494095D03*
X490158D03*
X486221D03*
X482284D03*
X478347D03*
X474410D03*
X470473D03*
X466536D03*
X462599D03*
X458662D03*
X454725D03*
X450787D03*
X509843Y222441D03*
X505906D03*
X501969D03*
X498032D03*
X494095D03*
X490158D03*
X486221D03*
X482284D03*
X478347D03*
X474410D03*
X470473D03*
X466536D03*
X462599D03*
X458662D03*
X454725D03*
X450787D03*
X509843Y226378D03*
X505906D03*
X501969D03*
X498032D03*
X494095D03*
X490158D03*
X486221D03*
X482284D03*
X478347D03*
X474410D03*
X470473D03*
X466536D03*
X462599D03*
X458662D03*
X454725D03*
X450787D03*
X509843Y230315D03*
X505906D03*
X501969D03*
X498032D03*
X494095D03*
X490158D03*
X486221D03*
X482284D03*
X478347D03*
X474410D03*
X470473D03*
X466536D03*
X462599D03*
X458662D03*
X454725D03*
X450787D03*
X509843Y234252D03*
X505906D03*
X501969D03*
X498032D03*
X494095D03*
X490158D03*
X486221D03*
X482284D03*
X478347D03*
X474410D03*
X470473D03*
X466536D03*
X462599D03*
X458662D03*
X454725D03*
X450787D03*
X456693Y236221D03*
X464567D03*
X472441D03*
X460630Y208662D03*
X468504D03*
X484252D03*
X476378D03*
X496063D03*
X456693Y212599D03*
X464567D03*
X503937Y216536D03*
X472441Y212599D03*
X480315D03*
X488189D03*
X507874D03*
Y236221D03*
X503937Y232284D03*
X507874Y228347D03*
X503937Y224410D03*
X507874Y220473D03*
X472441Y228347D03*
X464567D03*
X456693D03*
X480315D03*
X484252Y236221D03*
X488189Y232284D03*
X456693D03*
X464567D03*
X472441D03*
X480315D03*
X456693Y200788D03*
X464567D03*
X492126Y208662D03*
Y204725D03*
X500000D03*
X472441Y200788D03*
X480315D03*
X488189D03*
X492126D03*
X460630Y212599D03*
X468504D03*
X492126Y216536D03*
X476378Y212599D03*
X484252D03*
X492126D03*
X503937D03*
X507874Y208662D03*
X503937Y204725D03*
X507874D03*
X503937Y236221D03*
Y228347D03*
X492126Y220473D03*
X503937D03*
X511811Y208662D03*
X507874Y200788D03*
X511811D03*
X472441Y224410D03*
X464567D03*
X456693D03*
X480315D03*
X492126D03*
X488189D03*
X492126Y232284D03*
Y236221D03*
X500000Y200788D03*
X503937D03*
X456693Y220473D03*
Y216536D03*
X460630Y220473D03*
Y216536D03*
X464567Y220473D03*
Y216536D03*
X468504Y220473D03*
Y216536D03*
X472441Y220473D03*
Y216536D03*
X476378Y220473D03*
Y216536D03*
X480315Y220473D03*
Y216536D03*
X484252Y220473D03*
Y216536D03*
X488189Y220473D03*
Y216536D03*
X500000Y208662D03*
X503937D03*
X496063Y212599D03*
X500000D03*
X496063Y216536D03*
X500000D03*
X496063Y220473D03*
X500000D03*
X496063Y224410D03*
X500000D03*
X496063Y228347D03*
X500000D03*
X496063Y232284D03*
X500000D03*
X496063Y236221D03*
X500000D03*
X456693Y208662D03*
Y204725D03*
X460630D03*
Y200788D03*
X464567Y208662D03*
Y204725D03*
X468504D03*
Y200788D03*
X472441Y208662D03*
Y204725D03*
X476378D03*
Y200788D03*
X480315Y208662D03*
Y204725D03*
X484252D03*
Y200788D03*
X488189Y208662D03*
Y204725D03*
X509843Y238189D03*
X505906D03*
X501969D03*
X498032D03*
X494095D03*
X490158D03*
X486221D03*
X482284D03*
X478347D03*
X474410D03*
X470473D03*
X466536D03*
X462599D03*
X458662D03*
X454725D03*
X450787D03*
X509843Y242126D03*
X505906D03*
X501969D03*
X498032D03*
X494095D03*
X490158D03*
X486221D03*
X482284D03*
X478347D03*
X474410D03*
X470473D03*
X466536D03*
X462599D03*
X458662D03*
X454725D03*
X450787D03*
X509843Y246063D03*
X505906D03*
X501969D03*
X498032D03*
X494095D03*
X490158D03*
X486221D03*
X482284D03*
X478347D03*
X474410D03*
X470473D03*
X466536D03*
X462599D03*
X458662D03*
X454725D03*
X450787D03*
X509843Y250000D03*
X505906D03*
X501969D03*
X498032D03*
X494095D03*
X490158D03*
X486221D03*
X482284D03*
X478347D03*
X474410D03*
X470473D03*
X466536D03*
X462599D03*
X458662D03*
X454725D03*
X450787D03*
X509843Y253937D03*
X505906D03*
X501969D03*
X498032D03*
X494095D03*
X490158D03*
X486221D03*
X482284D03*
X478347D03*
X474410D03*
X470473D03*
X466536D03*
X462599D03*
X458662D03*
X454725D03*
X450787D03*
X509843Y257874D03*
X505906D03*
X501969D03*
X498032D03*
X494095D03*
X490158D03*
X486221D03*
X482284D03*
X478347D03*
X474410D03*
X470473D03*
X466536D03*
X462599D03*
X458662D03*
X454725D03*
X450787D03*
X509843Y261811D03*
X505906D03*
X501969D03*
X498032D03*
X494095D03*
X490158D03*
X486221D03*
X482284D03*
X478347D03*
X474410D03*
X470473D03*
X466536D03*
X462599D03*
X458662D03*
X454725D03*
X450787D03*
X509843Y265749D03*
X505906D03*
X501969D03*
X498032D03*
X494095D03*
X490158D03*
X486221D03*
X482284D03*
X478347D03*
X474410D03*
X470473D03*
X466536D03*
X462599D03*
X458662D03*
X454725D03*
X450787D03*
X509843Y269686D03*
X505906D03*
X501969D03*
X498032D03*
X494095D03*
X490158D03*
X486221D03*
X482284D03*
X478347D03*
X474410D03*
X470473D03*
X466536D03*
X462599D03*
X458662D03*
X454725D03*
X450787D03*
X509843Y273623D03*
X505906D03*
X501969D03*
X498032D03*
X494095D03*
X490158D03*
X486221D03*
X482284D03*
X478347D03*
X474410D03*
X470473D03*
X466536D03*
X462599D03*
X458662D03*
X454725D03*
X450787D03*
X509843Y277560D03*
X505906D03*
X501969D03*
X498032D03*
X494095D03*
X490158D03*
X486221D03*
X482284D03*
X478347D03*
X474410D03*
X470473D03*
X466536D03*
X462599D03*
X458662D03*
X454725D03*
X450787D03*
X509843Y281497D03*
X505906D03*
X501969D03*
X498032D03*
X494095D03*
X490158D03*
X486221D03*
X482284D03*
X478347D03*
X474410D03*
X470473D03*
X466536D03*
X462599D03*
X458662D03*
X454725D03*
X450787D03*
X509843Y285434D03*
X505906D03*
X501969D03*
X498032D03*
X494095D03*
X490158D03*
X486221D03*
X482284D03*
X478347D03*
X474410D03*
X470473D03*
X466536D03*
X462599D03*
X458662D03*
X454725D03*
X450787D03*
X509843Y289371D03*
X505906D03*
X501969D03*
X498032D03*
X494095D03*
X490158D03*
X486221D03*
X482284D03*
X478347D03*
X474410D03*
X470473D03*
X466536D03*
X462599D03*
X458662D03*
X454725D03*
X450787D03*
X509843Y293308D03*
X505906D03*
X501969D03*
X498032D03*
X494095D03*
X490158D03*
X486221D03*
X482284D03*
X478347D03*
X474410D03*
X470473D03*
X466536D03*
X462599D03*
X458662D03*
X454725D03*
X450787D03*
X509843Y297245D03*
X505906D03*
X501969D03*
X498032D03*
X494095D03*
X490158D03*
X486221D03*
X482284D03*
X478347D03*
X474410D03*
X470473D03*
X466536D03*
X462599D03*
X458662D03*
X454725D03*
X450787D03*
X468504Y299214D03*
X472442Y287402D03*
X480315Y295276D03*
X484252Y295277D03*
X476378Y291339D03*
X452755Y287402D03*
Y291340D03*
Y295277D03*
X503937Y255906D03*
X507874Y251969D03*
X503937Y248032D03*
X507874Y244095D03*
X503937Y240158D03*
X507874Y271654D03*
X503937Y267717D03*
X507874Y259843D03*
Y287402D03*
X503937Y283465D03*
X507874Y279528D03*
X503937Y275591D03*
Y299213D03*
X507874Y295276D03*
X503937Y291339D03*
X492126Y287402D03*
X484252Y271654D03*
Y279528D03*
X488189Y267717D03*
Y275591D03*
X492126Y271654D03*
Y279528D03*
X488189Y283465D03*
X484252Y259843D03*
Y251969D03*
Y244095D03*
X492126Y259843D03*
Y251969D03*
Y244095D03*
X464567Y299214D03*
X456693Y279528D03*
Y267718D03*
X464567D03*
X472441Y295276D03*
X503937Y251969D03*
Y244095D03*
Y271654D03*
Y259843D03*
Y287402D03*
Y279528D03*
Y295276D03*
X488189Y287402D03*
X492126Y291339D03*
X488189D03*
X472441Y240158D03*
X456693Y259843D03*
X464567Y240158D03*
X456693D03*
X480315Y267717D03*
Y271654D03*
Y275591D03*
Y279528D03*
Y283465D03*
X492126Y267717D03*
X488189Y271654D03*
X492126Y275591D03*
X488189Y279528D03*
X492126Y283465D03*
X480315Y259843D03*
Y240158D03*
Y244095D03*
Y248032D03*
Y251969D03*
Y255906D03*
X488189Y259843D03*
X492126Y240158D03*
X488189D03*
X492126Y248032D03*
X488189D03*
Y255906D03*
X452757Y279529D03*
X464567D03*
X472441Y275591D03*
Y267717D03*
Y283465D03*
Y259843D03*
Y251969D03*
X456693Y248032D03*
X464567D03*
Y259843D03*
X472441Y291339D03*
X464568Y287402D03*
X460630Y275592D03*
X464568D03*
X452756D03*
X456693Y255906D03*
X464567D03*
Y263780D03*
X456693D03*
X464567Y271655D03*
X456693D03*
X476379Y287402D03*
X472441Y299213D03*
X480315D03*
X488189D03*
X456693Y287402D03*
X460630Y283465D03*
X468504D03*
X468505Y287402D03*
X460631Y295277D03*
X456693Y299213D03*
X460630D03*
X480316Y287403D03*
X484252Y291340D03*
Y287402D03*
X488189Y295276D03*
X456694D03*
X496063Y255906D03*
X500000D03*
X496063Y259843D03*
X500000D03*
X496063Y267717D03*
X500000D03*
X496063Y240158D03*
X500000D03*
X496063Y244095D03*
X500000D03*
X496063Y271654D03*
X500000D03*
X496063Y248032D03*
X500000D03*
X496063Y251969D03*
X500000D03*
X496063Y275591D03*
X500000D03*
X496063Y279528D03*
X500000D03*
X496063Y283465D03*
X500000D03*
X496063Y287402D03*
X500000D03*
X507874Y255906D03*
X511811D03*
Y259843D03*
X507874Y267717D03*
X511811D03*
X507874Y240158D03*
X511811D03*
Y244095D03*
Y271654D03*
X507874Y248032D03*
X511811D03*
Y251969D03*
X507874Y275591D03*
X511811D03*
Y279528D03*
X507874Y283465D03*
X511811D03*
Y287402D03*
X480315Y291339D03*
X496063Y299213D03*
X500000D03*
X496063Y291339D03*
X500000D03*
X496063Y295276D03*
X500000D03*
X476378Y267717D03*
Y275591D03*
Y259843D03*
Y251969D03*
X472441Y244095D03*
X464567D03*
X456693D03*
Y291339D03*
X460630D03*
X509843Y301182D03*
X505906D03*
X501969D03*
X498032D03*
X494095D03*
X490158D03*
X486221D03*
X482284D03*
X478347D03*
X474410D03*
X470473D03*
X466536D03*
X462599D03*
X458662D03*
X454725D03*
X450787D03*
X509843Y305119D03*
X505906D03*
X501969D03*
X498032D03*
X494095D03*
X490158D03*
X486221D03*
X482284D03*
X478347D03*
X474410D03*
X470473D03*
X466536D03*
X462599D03*
X458662D03*
X454725D03*
X450787D03*
X509843Y309056D03*
X505906D03*
X501969D03*
X498032D03*
X494095D03*
X490158D03*
X486221D03*
X482284D03*
X478347D03*
X474410D03*
X470473D03*
X466536D03*
X462599D03*
X458662D03*
X454725D03*
X450787D03*
X509843Y312993D03*
X505906D03*
X501969D03*
X498032D03*
X494095D03*
X490158D03*
X486221D03*
X482284D03*
X478347D03*
X474410D03*
X470473D03*
X466536D03*
X462599D03*
X458662D03*
X454725D03*
X450787D03*
X501969Y316930D03*
X498032D03*
X494095D03*
X490158D03*
X486221D03*
X482284D03*
X478347D03*
X474410D03*
X470473D03*
X466536D03*
X462599D03*
X458662D03*
X454725D03*
X450787D03*
X501969Y320867D03*
X498032D03*
X494095D03*
X490158D03*
X486221D03*
X482284D03*
X478347D03*
X474410D03*
X470473D03*
X466536D03*
X462599D03*
X458662D03*
X454725D03*
X450787D03*
X501969Y324804D03*
X498032D03*
X494095D03*
X490158D03*
X486221D03*
X482284D03*
X478347D03*
X474410D03*
X470473D03*
X466536D03*
X462599D03*
X458662D03*
X454725D03*
X450787D03*
X500001Y314961D03*
X503937Y318898D03*
X488189Y307087D03*
X492126Y311024D03*
X460630Y307087D03*
X456693D03*
X460630Y311024D03*
X462599Y327204D03*
X456693Y311024D03*
Y314961D03*
X452755Y307087D03*
Y303150D03*
X456693Y318898D03*
X507874Y303150D03*
X472441D03*
X460630Y318898D03*
X468504D03*
X456693Y303150D03*
X476378Y318898D03*
X484252D03*
X492126D03*
X500000D03*
X496063Y307087D03*
X480315Y303150D03*
X492126D03*
X507874Y318898D03*
Y307087D03*
X511811D03*
X503937Y303150D03*
X484252D03*
X496063Y318898D03*
X488189Y311024D03*
X484252Y307087D03*
Y314961D03*
X476378D03*
X468504D03*
X507874D03*
X492126D03*
X500000Y311025D03*
X460630Y314961D03*
X496063D03*
X476378Y311024D03*
X472441Y307087D03*
X488189Y303150D03*
X500000Y307088D03*
X503937Y311024D03*
X468504Y303151D03*
X460630Y303150D03*
X464567Y303151D03*
X503937Y307087D03*
X507874Y311024D03*
X464567Y307088D03*
X468505D03*
X472441Y314961D03*
X492126Y307087D03*
X496063Y311024D03*
X464567Y311025D03*
Y318898D03*
X472441D03*
X496063Y303150D03*
X500000D03*
X470473Y327204D03*
X468504Y311024D03*
X488189Y322835D03*
X513780Y214567D03*
Y218504D03*
Y222441D03*
Y226378D03*
Y230315D03*
Y234252D03*
X517000Y226370D03*
Y218500D03*
Y234252D03*
X513780Y238189D03*
Y242126D03*
Y246063D03*
Y250000D03*
Y253937D03*
Y257874D03*
Y261811D03*
Y265749D03*
Y269686D03*
Y273623D03*
Y277560D03*
Y281497D03*
Y285434D03*
Y289371D03*
Y293308D03*
Y297245D03*
X517500Y297218D03*
X518647Y288943D03*
X515748Y240158D03*
Y267717D03*
Y255906D03*
Y248032D03*
Y283465D03*
Y275591D03*
Y259843D03*
Y244095D03*
Y271654D03*
Y251969D03*
Y279528D03*
Y287402D03*
X513780Y301182D03*
Y305119D03*
Y309056D03*
Y312993D03*
X515748Y318898D03*
Y307087D03*
X516500Y313000D03*
X666928Y144880D03*
X682675Y132281D03*
X688974D03*
X660630Y122834D03*
X660629Y119685D03*
X663779Y122834D03*
Y119685D03*
X670079Y122835D03*
X670078Y119685D03*
X673229Y122835D03*
X673228Y119685D03*
X679528Y122835D03*
X679527Y119685D03*
X682678Y122835D03*
X682677Y119685D03*
X688977Y122835D03*
X688976Y119685D03*
X692126Y122835D03*
Y119686D03*
G54D99*
X621320Y299289D03*
Y297319D03*
Y295354D03*
X605020D03*
Y297319D03*
Y299289D03*
X614220Y361815D03*
X605020D03*
X621320Y341633D03*
Y339668D03*
Y337698D03*
Y335728D03*
Y333763D03*
X605020D03*
Y335728D03*
Y337698D03*
Y339668D03*
Y341633D03*
X621320Y303224D03*
Y301259D03*
X605020D03*
Y303224D03*
X614220Y367725D03*
Y365755D03*
Y363785D03*
X605020D03*
Y365755D03*
Y367725D03*
X614220Y390105D03*
Y388135D03*
Y386165D03*
Y384195D03*
X605020D03*
Y386165D03*
Y388135D03*
Y390105D03*
X762337Y278194D03*
Y280164D03*
Y282134D03*
Y284104D03*
X771537D03*
Y282134D03*
Y280164D03*
Y278194D03*
M02*
